G04 ================== begin FILE IDENTIFICATION RECORD ==================*
G04 Layout Name:  15105-sa.brd*
G04 Film Name:    L2GND*
G04 File Format:  Gerber RS274X*
G04 File Origin:  Cadence Allegro 16.5-S056*
G04 Origin Date:  Wed Nov 16 02:02:14 2016*
G04 *
G04 Layer:  VIA CLASS/L2GND*
G04 Layer:  PIN/L2GND*
G04 Layer:  ETCH/L2GND*
G04 Layer:  DRAWING FORMAT/LAYER_PCB_STORY*
G04 Layer:  DRAWING FORMAT/LAYER_L2GND*
G04 *
G04 Offset:    (0.00 0.00)*
G04 Mirror:    No*
G04 Mode:      Negative*
G04 Rotation:  0*
G04 FullContactRelief:  No*
G04 UndefLineWidth:     6.00*
G04 ================== end FILE IDENTIFICATION RECORD ====================*
%FSLAX35Y35*MOIN*%
%IR0*IPPOS*OFA0.00000B0.00000*MIA0B0*SFA1.00000B1.00000*%
%AMMACRO19*
4,1,16,.09696,-.02,
.092014,-.036533,
.084272,-.051956,
.07397,-.065801,
.06142,-.077646,
.047004,-.087131,
.031159,-.09397,
.02,-.09696,
.02,-.10206,
.037419,-.097037,
.0537,-.089065,
.068351,-.078387,
.080924,-.065327,
.091038,-.050282,
.098387,-.033709,
.10206,-.02,
.09696,-.02,
90.*
4,1,16,-.02,-.09696,
-.036533,-.092014,
-.051956,-.084272,
-.065801,-.07397,
-.077646,-.06142,
-.087131,-.047004,
-.09397,-.031159,
-.09696,-.02,
-.10206,-.02,
-.097037,-.037419,
-.089065,-.0537,
-.078387,-.068351,
-.065327,-.080924,
-.050282,-.091038,
-.033709,-.098387,
-.02,-.10206,
-.02,-.09696,
90.*
4,1,16,-.09696,.02,
-.092014,.036533,
-.084272,.051956,
-.07397,.065801,
-.06142,.077646,
-.047004,.087131,
-.031159,.09397,
-.02,.09696,
-.02,.10206,
-.037419,.097037,
-.0537,.089065,
-.068351,.078387,
-.080924,.065327,
-.091038,.050282,
-.098387,.033709,
-.10206,.02,
-.09696,.02,
90.*
4,1,16,.02,.09696,
.036533,.092014,
.051956,.084272,
.065801,.07397,
.077646,.06142,
.087131,.047004,
.09397,.031159,
.09696,.02,
.10206,.02,
.097037,.037419,
.089065,.0537,
.078387,.068351,
.065327,.080924,
.050282,.091038,
.033709,.098387,
.02,.10206,
.02,.09696,
90.*
%
%ADD19MACRO19*%
%AMMACRO40*
4,1,13,.02632,.01218,
.028035,.007425,
.028899,.002443,
.028884,-.002612,
.027991,-.007588,
.02632,-.01218,
.03005,-.01591,
.032356,-.01045,
.033679,-.004673,
.033979,.001247,
.033246,.007128,
.031504,.012793,
.03005,.01591,
.02632,.01218,
90.*
4,1,13,.01218,-.02632,
.007425,-.028035,
.002443,-.028899,
-.002612,-.028884,
-.007588,-.027991,
-.01218,-.02632,
-.01591,-.03005,
-.01045,-.032356,
-.004673,-.033679,
.001247,-.033979,
.007128,-.033246,
.012793,-.031504,
.01591,-.03005,
.01218,-.02632,
90.*
4,1,13,-.02632,-.01218,
-.028035,-.007425,
-.028899,-.002443,
-.028884,.002612,
-.027991,.007588,
-.02632,.01218,
-.03005,.01591,
-.032356,.01045,
-.033679,.004673,
-.033979,-.001247,
-.033246,-.007128,
-.031504,-.012793,
-.03005,-.01591,
-.02632,-.01218,
90.*
4,1,13,-.01218,.02632,
-.007425,.028035,
-.002443,.028899,
.002612,.028884,
.007588,.027991,
.01218,.02632,
.01591,.03005,
.01045,.032356,
.004673,.033679,
-.001247,.033979,
-.007128,.033246,
-.012793,.031504,
-.01591,.03005,
-.01218,.02632,
90.*
%
%ADD40MACRO40*%
%AMMACRO29*
4,1,13,.02632,.01218,
.028035,.007425,
.028899,.002443,
.028884,-.002612,
.027991,-.007588,
.02632,-.01218,
.03005,-.01591,
.032356,-.01045,
.033679,-.004673,
.033979,.001247,
.033246,.007128,
.031504,.012793,
.03005,.01591,
.02632,.01218,
0.0*
4,1,13,.01218,-.02632,
.007425,-.028035,
.002443,-.028899,
-.002612,-.028884,
-.007588,-.027991,
-.01218,-.02632,
-.01591,-.03005,
-.01045,-.032356,
-.004673,-.033679,
.001247,-.033979,
.007128,-.033246,
.012793,-.031504,
.01591,-.03005,
.01218,-.02632,
0.0*
4,1,13,-.02632,-.01218,
-.028035,-.007425,
-.028899,-.002443,
-.028884,.002612,
-.027991,.007588,
-.02632,.01218,
-.03005,.01591,
-.032356,.01045,
-.033679,.004673,
-.033979,-.001247,
-.033246,-.007128,
-.031504,-.012793,
-.03005,-.01591,
-.02632,-.01218,
0.0*
4,1,13,-.01218,.02632,
-.007425,.028035,
-.002443,.028899,
.002612,.028884,
.007588,.027991,
.01218,.02632,
.01591,.03005,
.01045,.032356,
.004673,.033679,
-.001247,.033979,
-.007128,.033246,
-.012793,.031504,
-.01591,.03005,
-.01218,.02632,
0.0*
%
%ADD29MACRO29*%
%ADD14C,.03*%
%ADD24C,.032*%
%ADD21C,.06*%
%ADD36C,.043*%
%ADD32C,.07*%
%ADD38C,.063*%
%ADD26C,.036*%
%ADD25C,.028*%
%ADD18C,.064*%
%ADD23C,.066*%
%ADD31C,.058*%
%ADD28C,.068*%
%ADD12C,.078*%
%AMMACRO34*
4,1,14,.02707,.01293,
.028904,.008033,
.02986,.002892,
.029908,-.002337,
.029048,-.007495,
.027305,-.012426,
.02707,-.01293,
.03079,-.01665,
.033213,-.01105,
.034628,-.005115,
.03499,.000976,
.034289,.007037,
.032546,.012884,
.03079,.01665,
.02707,.01293,
270.*
4,1,14,.01293,-.02707,
.008033,-.028904,
.002892,-.02986,
-.002337,-.029908,
-.007495,-.029048,
-.012426,-.027305,
-.01293,-.02707,
-.01665,-.03079,
-.01105,-.033213,
-.005115,-.034628,
.000976,-.03499,
.007037,-.034289,
.012884,-.032546,
.01665,-.03079,
.01293,-.02707,
270.*
4,1,14,-.02707,-.01293,
-.028904,-.008033,
-.02986,-.002892,
-.029908,.002337,
-.029048,.007495,
-.027305,.012426,
-.02707,.01293,
-.03079,.01665,
-.033213,.01105,
-.034628,.005115,
-.03499,-.000976,
-.034289,-.007037,
-.032546,-.012884,
-.03079,-.01665,
-.02707,-.01293,
270.*
4,1,14,-.01293,.02707,
-.008033,.028904,
-.002892,.02986,
.002337,.029908,
.007495,.029048,
.012426,.027305,
.01293,.02707,
.01665,.03079,
.01105,.033213,
.005115,.034628,
-.000976,.03499,
-.007037,.034289,
-.012884,.032546,
-.01665,.03079,
-.01293,.02707,
270.*
%
%ADD34MACRO34*%
%AMMACRO20*
4,1,15,.00398,.00044,
.003999,.000208,
.004004,-.000025,
.003996,-.000258,
.00398,-.00044,
.00483,-.00129,
.004897,-.001007,
.004947,-.000721,
.004981,-.000432,
.004997,-.000141,
.004997,.000149,
.00498,.00044,
.004946,.000729,
.004895,.001015,
.00483,.00129,
.00398,.00044,
90.*
4,1,15,.00044,-.00398,
.000208,-.003999,
-.000025,-.004004,
-.000258,-.003996,
-.00044,-.00398,
-.00129,-.00483,
-.001007,-.004897,
-.000721,-.004947,
-.000432,-.004981,
-.000141,-.004997,
.000149,-.004997,
.00044,-.00498,
.000729,-.004946,
.001015,-.004895,
.00129,-.00483,
.00044,-.00398,
90.*
4,1,15,-.00398,-.00044,
-.003999,-.000208,
-.004004,.000025,
-.003996,.000258,
-.00398,.00044,
-.00483,.00129,
-.004897,.001007,
-.004947,.000721,
-.004981,.000432,
-.004997,.000141,
-.004997,-.000149,
-.00498,-.00044,
-.004946,-.000729,
-.004895,-.001015,
-.00483,-.00129,
-.00398,-.00044,
90.*
4,1,15,-.00044,.00398,
-.000208,.003999,
.000025,.004004,
.000258,.003996,
.00044,.00398,
.00129,.00483,
.001007,.004897,
.000721,.004947,
.000432,.004981,
.000141,.004997,
-.000149,.004997,
-.00044,.00498,
-.000729,.004946,
-.001015,.004895,
-.00129,.00483,
-.00044,.00398,
90.*
%
%ADD20MACRO20*%
%AMMACRO11*
4,1,15,.00398,.00044,
.003999,.000208,
.004004,-.000025,
.003996,-.000258,
.00398,-.00044,
.00483,-.00129,
.004897,-.001007,
.004947,-.000721,
.004981,-.000432,
.004997,-.000141,
.004997,.000149,
.00498,.00044,
.004946,.000729,
.004895,.001015,
.00483,.00129,
.00398,.00044,
0.0*
4,1,15,.00044,-.00398,
.000208,-.003999,
-.000025,-.004004,
-.000258,-.003996,
-.00044,-.00398,
-.00129,-.00483,
-.001007,-.004897,
-.000721,-.004947,
-.000432,-.004981,
-.000141,-.004997,
.000149,-.004997,
.00044,-.00498,
.000729,-.004946,
.001015,-.004895,
.00129,-.00483,
.00044,-.00398,
0.0*
4,1,15,-.00398,-.00044,
-.003999,-.000208,
-.004004,.000025,
-.003996,.000258,
-.00398,.00044,
-.00483,.00129,
-.004897,.001007,
-.004947,.000721,
-.004981,.000432,
-.004997,.000141,
-.004997,-.000149,
-.00498,-.00044,
-.004946,-.000729,
-.004895,-.001015,
-.00483,-.00129,
-.00398,-.00044,
0.0*
4,1,15,-.00044,.00398,
-.000208,.003999,
.000025,.004004,
.000258,.003996,
.00044,.00398,
.00129,.00483,
.001007,.004897,
.000721,.004947,
.000432,.004981,
.000141,.004997,
-.000149,.004997,
-.00044,.00498,
-.000729,.004946,
-.001015,.004895,
-.00129,.00483,
-.00044,.00398,
0.0*
%
%ADD11MACRO11*%
%AMMACRO39*
4,1,13,.02442,.01028,
.025834,.005883,
.026463,.001308,
.026288,-.003307,
.025315,-.007822,
.02442,-.01028,
.02819,-.01405,
.030201,-.008941,
.031295,-.003561,
.031438,.001927,
.030626,.007357,
.028883,.012564,
.02819,.01405,
.02442,.01028,
180.*
4,1,13,.01028,-.02442,
.005883,-.025834,
.001308,-.026463,
-.003307,-.026288,
-.007822,-.025315,
-.01028,-.02442,
-.01405,-.02819,
-.008941,-.030201,
-.003561,-.031295,
.001927,-.031438,
.007357,-.030626,
.012564,-.028883,
.01405,-.02819,
.01028,-.02442,
180.*
4,1,13,-.02442,-.01028,
-.025834,-.005883,
-.026463,-.001308,
-.026288,.003307,
-.025315,.007822,
-.02442,.01028,
-.02819,.01405,
-.030201,.008941,
-.031295,.003561,
-.031438,-.001927,
-.030626,-.007357,
-.028883,-.012564,
-.02819,-.01405,
-.02442,-.01028,
180.*
4,1,13,-.01028,.02442,
-.005883,.025834,
-.001308,.026463,
.003307,.026288,
.007822,.025315,
.01028,.02442,
.01405,.02819,
.008941,.030201,
.003561,.031295,
-.001927,.031438,
-.007357,.030626,
-.012564,.028883,
-.01405,.02819,
-.01028,.02442,
180.*
%
%ADD39MACRO39*%
%AMMACRO37*
4,1,13,.02632,.01218,
.028035,.007425,
.028899,.002443,
.028884,-.002612,
.027991,-.007588,
.02632,-.01218,
.03005,-.01591,
.032356,-.01045,
.033679,-.004673,
.033979,.001247,
.033246,.007128,
.031504,.012793,
.03005,.01591,
.02632,.01218,
270.*
4,1,13,.01218,-.02632,
.007425,-.028035,
.002443,-.028899,
-.002612,-.028884,
-.007588,-.027991,
-.01218,-.02632,
-.01591,-.03005,
-.01045,-.032356,
-.004673,-.033679,
.001247,-.033979,
.007128,-.033246,
.012793,-.031504,
.01591,-.03005,
.01218,-.02632,
270.*
4,1,13,-.02632,-.01218,
-.028035,-.007425,
-.028899,-.002443,
-.028884,.002612,
-.027991,.007588,
-.02632,.01218,
-.03005,.01591,
-.032356,.01045,
-.033679,.004673,
-.033979,-.001247,
-.033246,-.007128,
-.031504,-.012793,
-.03005,-.01591,
-.02632,-.01218,
270.*
4,1,13,-.01218,.02632,
-.007425,.028035,
-.002443,.028899,
.002612,.028884,
.007588,.027991,
.01218,.02632,
.01591,.03005,
.01045,.032356,
.004673,.033679,
-.001247,.033979,
-.007128,.033246,
-.012793,.031504,
-.01591,.03005,
-.01218,.02632,
270.*
%
%ADD37MACRO37*%
%AMMACRO33*
4,1,13,.02632,.01218,
.028035,.007425,
.028899,.002443,
.028884,-.002612,
.027991,-.007588,
.02632,-.01218,
.03005,-.01591,
.032356,-.01045,
.033679,-.004673,
.033979,.001247,
.033246,.007128,
.031504,.012793,
.03005,.01591,
.02632,.01218,
180.*
4,1,13,.01218,-.02632,
.007425,-.028035,
.002443,-.028899,
-.002612,-.028884,
-.007588,-.027991,
-.01218,-.02632,
-.01591,-.03005,
-.01045,-.032356,
-.004673,-.033679,
.001247,-.033979,
.007128,-.033246,
.012793,-.031504,
.01591,-.03005,
.01218,-.02632,
180.*
4,1,13,-.02632,-.01218,
-.028035,-.007425,
-.028899,-.002443,
-.028884,.002612,
-.027991,.007588,
-.02632,.01218,
-.03005,.01591,
-.032356,.01045,
-.033679,.004673,
-.033979,-.001247,
-.033246,-.007128,
-.031504,-.012793,
-.03005,-.01591,
-.02632,-.01218,
180.*
4,1,13,-.01218,.02632,
-.007425,.028035,
-.002443,.028899,
.002612,.028884,
.007588,.027991,
.01218,.02632,
.01591,.03005,
.01045,.032356,
.004673,.033679,
-.001247,.033979,
-.007128,.033246,
-.012793,.031504,
-.01591,.03005,
-.01218,.02632,
180.*
%
%ADD33MACRO33*%
%ADD10C,.114*%
%ADD16C,.19*%
%ADD22C,.119*%
%ADD17C,.156*%
%ADD30C,.166*%
%AMMACRO15*
4,1,15,.00398,.00044,
.003999,.000208,
.004004,-.000025,
.003996,-.000258,
.00398,-.00044,
.00483,-.00129,
.004897,-.001007,
.004947,-.000721,
.004981,-.000432,
.004997,-.000141,
.004997,.000149,
.00498,.00044,
.004946,.000729,
.004895,.001015,
.00483,.00129,
.00398,.00044,
270.*
4,1,15,.00044,-.00398,
.000208,-.003999,
-.000025,-.004004,
-.000258,-.003996,
-.00044,-.00398,
-.00129,-.00483,
-.001007,-.004897,
-.000721,-.004947,
-.000432,-.004981,
-.000141,-.004997,
.000149,-.004997,
.00044,-.00498,
.000729,-.004946,
.001015,-.004895,
.00129,-.00483,
.00044,-.00398,
270.*
4,1,15,-.00398,-.00044,
-.003999,-.000208,
-.004004,.000025,
-.003996,.000258,
-.00398,.00044,
-.00483,.00129,
-.004897,.001007,
-.004947,.000721,
-.004981,.000432,
-.004997,.000141,
-.004997,-.000149,
-.00498,-.00044,
-.004946,-.000729,
-.004895,-.001015,
-.00483,-.00129,
-.00398,-.00044,
270.*
4,1,15,-.00044,.00398,
-.000208,.003999,
.000025,.004004,
.000258,.003996,
.00044,.00398,
.00129,.00483,
.001007,.004897,
.000721,.004947,
.000432,.004981,
.000141,.004997,
-.000149,.004997,
-.00044,.00498,
-.000729,.004946,
-.001015,.004895,
-.00129,.00483,
-.00044,.00398,
270.*
%
%ADD15MACRO15*%
%AMMACRO35*
4,1,14,.05302,.02473,
.056509,.015147,
.058281,.005105,
.058282,-.005093,
.056512,-.015136,
.053025,-.02472,
.05302,-.02473,
.05676,-.02847,
.060841,-.018181,
.063074,-.00734,
.063391,.003724,
.061781,.014675,
.058294,.025181,
.05676,.02847,
.05302,.02473,
0.0*
4,1,14,.02473,-.05302,
.015147,-.056509,
.005105,-.058281,
-.005093,-.058282,
-.015136,-.056512,
-.02472,-.053025,
-.02473,-.05302,
-.02847,-.05676,
-.018181,-.060841,
-.00734,-.063074,
.003724,-.063391,
.014675,-.061781,
.025181,-.058294,
.02847,-.05676,
.02473,-.05302,
0.0*
4,1,14,-.05302,-.02473,
-.056509,-.015147,
-.058281,-.005105,
-.058282,.005093,
-.056512,.015136,
-.053025,.02472,
-.05302,.02473,
-.05676,.02847,
-.060841,.018181,
-.063074,.00734,
-.063391,-.003724,
-.061781,-.014675,
-.058294,-.025181,
-.05676,-.02847,
-.05302,-.02473,
0.0*
4,1,14,-.02473,.05302,
-.015147,.056509,
-.005105,.058281,
.005093,.058282,
.015136,.056512,
.02472,.053025,
.02473,.05302,
.02847,.05676,
.018181,.060841,
.00734,.063074,
-.003724,.063391,
-.014675,.061781,
-.025181,.058294,
-.02847,.05676,
-.02473,.05302,
0.0*
%
%ADD35MACRO35*%
%AMMACRO13*
4,1,13,.03683,.01561,
.038981,.008977,
.039948,.002072,
.039701,-.004896,
.038247,-.011716,
.03683,-.01561,
.04061,-.01939,
.04336,-.012044,
.044793,-.004331,
.044864,.003513,
.043573,.01125,
.040957,.018645,
.04061,.01939,
.03683,.01561,
0.0*
4,1,13,.01561,-.03683,
.008977,-.038981,
.002072,-.039948,
-.004896,-.039701,
-.011716,-.038247,
-.01561,-.03683,
-.01939,-.04061,
-.012044,-.04336,
-.004331,-.044793,
.003513,-.044864,
.01125,-.043573,
.018645,-.040957,
.01939,-.04061,
.01561,-.03683,
0.0*
4,1,13,-.03683,-.01561,
-.038981,-.008977,
-.039948,-.002072,
-.039701,.004896,
-.038247,.011716,
-.03683,.01561,
-.04061,.01939,
-.04336,.012044,
-.044793,.004331,
-.044864,-.003513,
-.043573,-.01125,
-.040957,-.018645,
-.04061,-.01939,
-.03683,-.01561,
0.0*
4,1,13,-.01561,.03683,
-.008977,.038981,
-.002072,.039948,
.004896,.039701,
.011716,.038247,
.01561,.03683,
.01939,.04061,
.012044,.04336,
.004331,.044793,
-.003513,.044864,
-.01125,.043573,
-.018645,.040957,
-.01939,.04061,
-.01561,.03683,
0.0*
%
%ADD13MACRO13*%
%AMMACRO27*
4,1,13,.02556,.01142,
.027155,.006808,
.027924,.001989,
.027846,-.00289,
.026921,-.007681,
.02556,-.01142,
.02931,-.01517,
.031499,-.00985,
.032731,-.004231,
.032968,.001517,
.032204,.007219,
.030461,.012702,
.02931,.01517,
.02556,.01142,
0.0*
4,1,13,.01142,-.02556,
.006808,-.027155,
.001989,-.027924,
-.00289,-.027846,
-.007681,-.026921,
-.01142,-.02556,
-.01517,-.02931,
-.00985,-.031499,
-.004231,-.032731,
.001517,-.032968,
.007219,-.032204,
.012702,-.030461,
.01517,-.02931,
.01142,-.02556,
0.0*
4,1,13,-.02556,-.01142,
-.027155,-.006808,
-.027924,-.001989,
-.027846,.00289,
-.026921,.007681,
-.02556,.01142,
-.02931,.01517,
-.031499,.00985,
-.032731,.004231,
-.032968,-.001517,
-.032204,-.007219,
-.030461,-.012702,
-.02931,-.01517,
-.02556,-.01142,
0.0*
4,1,13,-.01142,.02556,
-.006808,.027155,
-.001989,.027924,
.00289,.027846,
.007681,.026921,
.01142,.02556,
.01517,.02931,
.00985,.031499,
.004231,.032731,
-.001517,.032968,
-.007219,.032204,
-.012702,.030461,
-.01517,.02931,
-.01142,.02556,
0.0*
%
%ADD27MACRO27*%
%ADD41C,.02*%
%ADD42C,.006*%
%ADD54C,.06204*%
%ADD51C,.06404*%
%ADD47C,.05604*%
%ADD45C,.11004*%
%ADD49C,.3151*%
%ADD46C,.15204*%
%ADD48C,.31532*%
%ADD53C,.31506*%
%ADD50C,.31534*%
%ADD44O,.09222X.04822*%
%ADD52R,.04102X.04678*%
%ADD43O,.09224X.04824*%
G75*
%LPD*%
G75*
G36*
G01X-6000Y-25685D02*
X1406000D01*
Y903637D01*
X-6000D01*
Y-25685D01*
G37*
%LPC*%
G75*
G36*
G01X3937Y837547D02*
X100000D01*
G03X108122Y845669I0J8122D01*
G01Y870618D01*
X110237D01*
G03X115209Y875590I-1J4973D01*
G01Y883398D01*
X288732D01*
Y876377D01*
G03X288826Y875176I7725J0D01*
G03X295420Y868723I7631J1202D01*
G03X297493I1037J7261D01*
G03X304181Y876378I-1037J7655D01*
G01Y883398D01*
X439909D01*
Y875590D01*
G03X444881Y870618I4973J1D01*
G01X446996D01*
Y845669D01*
G03X455118Y837547I8122J0D01*
G01X517323D01*
G03X525445Y845669I0J8122D01*
G01Y870618D01*
X527560D01*
G03X532532Y875590I-1J4973D01*
G01Y883398D01*
X706055D01*
Y876377D01*
G03X706149Y875176I7725J0D01*
G03X712743Y868723I7631J1202D01*
G03X714816I1037J7261D01*
G03X721504Y876378I-1037J7655D01*
G01Y883398D01*
X857232D01*
Y875590D01*
G03X862204Y870618I4973J1D01*
G01X864319D01*
Y845669D01*
G03X872441Y837547I8122J0D01*
G01X902134D01*
G02X918815Y820866I0J-16681D01*
G01Y650669D01*
G03X926819Y642665I8004J0D01*
G01X983748D01*
G03X991752Y650669I0J8004D01*
G01Y820866D01*
G02X1008433Y837547I16681J0D01*
G01X1013386D01*
G03X1021508Y845669I0J8122D01*
G01Y870618D01*
X1023623D01*
G03X1028595Y875590I-1J4973D01*
G01Y883398D01*
X1202118D01*
Y876377D01*
G03X1202212Y875176I7725J0D01*
G03X1208806Y868723I7631J1202D01*
G03X1210879I1036J7261D01*
G03X1217567Y876378I-1037J7655D01*
G01Y883398D01*
X1353295D01*
Y875590D01*
G03X1358267Y870618I4973J1D01*
G01X1360382D01*
Y845669D01*
G03X1368504Y837547I8122J0D01*
G01X1396063D01*
G02X1396996Y836614I0J-933D01*
G01Y76626D01*
X1396653D01*
G03X1391681Y71654I0J-4972D01*
G01Y40157D01*
G03X1396653Y35185I4972J0D01*
G01X1396996D01*
Y3937D01*
G02X1396063Y3004I-933J0D01*
G01X1310039D01*
G03X1303098Y-3937I0J-6941D01*
G01Y-15748D01*
G02X1302165Y-16681I-933J0D01*
G01X486762D01*
G02X481892Y-11811I0J4870D01*
G01Y-7874D01*
G03X471014Y3004I-10878J0D01*
G01X212402D01*
G02X207532Y7874I0J4870D01*
G01Y94528D01*
G03X196654Y105406I-10878J0D01*
G01X7874D01*
G02X3004Y110276I0J4870D01*
G01Y836614D01*
G02X3937Y837547I933J0D01*
G37*
%LPD*%
G75*
G36*
G01X115226Y418475D02*
X115233Y418468D01*
X112119Y415354D01*
X112115D01*
X112113Y415356D01*
X112107D01*
G02X108619Y418688I-1701J1711D01*
G01X108694Y418775D01*
X108691Y418778D01*
X111807Y421894D01*
X111810Y421891D01*
X111897Y421966D01*
G02X115226Y418475I1621J-1787D01*
G37*
G36*
G01X621794Y85929D02*
X621802Y85934D01*
X624757Y80419D01*
X624754Y80416D01*
X624751Y80414D01*
X624779Y80355D01*
G02X620463Y77990I-2202J-1102D01*
G01X620402Y78084D01*
X620399Y78082D01*
X617444Y83599D01*
X617447Y83601D01*
X617407Y83691D01*
G02X621794Y85929I2217J1073D01*
G37*
G36*
G01X542707Y77990D02*
X542646Y78084D01*
X542643Y78082D01*
X539688Y83597D01*
X539691Y83600D01*
X539694Y83602D01*
X539666Y83661D01*
G02X544038Y85929I2202J1103D01*
G01X544046Y85934D01*
X547001Y80417D01*
X546998Y80415D01*
X547038Y80325D01*
G02X542707Y77990I-2217J-1072D01*
G37*
G36*
G01X1343726Y873166D02*
X1340525D01*
G02X1340526Y877186I1J2010D01*
G01X1343726D01*
G02Y873166I0J-2010D01*
G37*
G36*
G01X1331128D02*
X1327928D01*
G02Y877186I0J2010D01*
G01X1331129D01*
G02X1331128Y873166I-1J-2010D01*
G37*
G36*
G01X1318529D02*
X1315329D01*
G02Y877186I0J2010D01*
G01X1318530D01*
G02X1318529Y873166I-1J-2010D01*
G37*
G36*
G01X1305931D02*
X1302731D01*
G02Y877186I0J2010D01*
G01X1305932D01*
G02X1305931Y873166I-1J-2010D01*
G37*
G36*
G01X1293333D02*
X1290133D01*
G02Y877186I0J2010D01*
G01X1293334D01*
G02X1293333Y873166I-1J-2010D01*
G37*
G36*
G01X1280734D02*
X1277534D01*
G02Y877186I0J2010D01*
G01X1280735D01*
G02X1280734Y873166I-1J-2010D01*
G37*
G36*
G01X1268136D02*
X1264936D01*
G02Y877186I0J2010D01*
G01X1268137D01*
G02X1268136Y873166I-1J-2010D01*
G37*
G36*
G01X1255537D02*
X1252337D01*
G02Y877186I0J2010D01*
G01X1255538D01*
G02X1255537Y873166I-1J-2010D01*
G37*
G36*
G01X1242939D02*
X1239739D01*
G02Y877186I0J2010D01*
G01X1242940D01*
G02X1242939Y873166I-1J-2010D01*
G37*
G36*
G01X1230340D02*
X1227140D01*
G02Y877186I0J2010D01*
G01X1230341D01*
G02X1230340Y873166I-1J-2010D01*
G37*
G36*
G01X1186246D02*
X1183046D01*
G02Y877186I0J2010D01*
G01X1186247D01*
G02X1186246Y873166I-1J-2010D01*
G37*
G36*
G01X1164199D02*
X1160999D01*
G02Y877186I0J2010D01*
G01X1164200D01*
G02X1164199Y873166I-1J-2010D01*
G37*
G36*
G01X1151600D02*
X1148400D01*
G02Y877186I0J2010D01*
G01X1151601D01*
G02X1151600Y873166I-1J-2010D01*
G37*
G36*
G01X1139002D02*
X1135802D01*
G02Y877186I0J2010D01*
G01X1139003D01*
G02X1139002Y873166I-1J-2010D01*
G37*
G36*
G01X1126403D02*
X1123203D01*
G02Y877186I0J2010D01*
G01X1126404D01*
G02X1126403Y873166I-1J-2010D01*
G37*
G36*
G01X1113805D02*
X1110605D01*
G02Y877186I0J2010D01*
G01X1113806D01*
G02X1113805Y873166I-1J-2010D01*
G37*
G36*
G01X1101207D02*
X1098007D01*
G02Y877186I0J2010D01*
G01X1101208D01*
G02X1101207Y873166I-1J-2010D01*
G37*
G36*
G01X1088608D02*
X1085408D01*
G02Y877186I0J2010D01*
G01X1088609D01*
G02X1088608Y873166I-1J-2010D01*
G37*
G36*
G01X1076010D02*
X1072810D01*
G02Y877186I0J2010D01*
G01X1076011D01*
G02X1076010Y873166I-1J-2010D01*
G37*
G36*
G01X1050813D02*
X1047613D01*
G02Y877186I0J2010D01*
G01X1050814D01*
G02X1050813Y873166I-1J-2010D01*
G37*
G36*
G01X1038214D02*
X1035014D01*
G02Y877186I0J2010D01*
G01X1038215D01*
G02X1038214Y873166I-1J-2010D01*
G37*
G36*
G01X847663D02*
X844463D01*
G02Y877186I0J2010D01*
G01X847664D01*
G02X847663Y873166I-1J-2010D01*
G37*
G36*
G01X835065D02*
X831865D01*
G02Y877186I0J2010D01*
G01X835066D01*
G02X835065Y873166I-1J-2010D01*
G37*
G36*
G01X809868D02*
X806668D01*
G02Y877186I0J2010D01*
G01X809869D01*
G02X809868Y873166I-1J-2010D01*
G37*
G36*
G01X797270D02*
X794070D01*
G02Y877186I0J2010D01*
G01X797271D01*
G02X797270Y873166I-1J-2010D01*
G37*
G36*
G01X784671D02*
X781471D01*
G02Y877186I0J2010D01*
G01X784672D01*
G02X784671Y873166I-1J-2010D01*
G37*
G36*
G01X772073D02*
X768873D01*
G02Y877186I0J2010D01*
G01X772074D01*
G02X772073Y873166I-1J-2010D01*
G37*
G36*
G01X759474D02*
X756274D01*
G02Y877186I0J2010D01*
G01X759475D01*
G02X759474Y873166I-1J-2010D01*
G37*
G36*
G01X746876D02*
X743676D01*
G02Y877186I0J2010D01*
G01X746877D01*
G02X746876Y873166I-1J-2010D01*
G37*
G36*
G01X734277D02*
X731076D01*
G02X731077Y877186I1J2010D01*
G01X734277D01*
G02Y873166I0J-2010D01*
G37*
G36*
G01X690183D02*
X686983D01*
G02Y877186I0J2010D01*
G01X690184D01*
G02X690183Y873166I-1J-2010D01*
G37*
G36*
G01X677585D02*
X674385D01*
G02Y877186I0J2010D01*
G01X677586D01*
G02X677585Y873166I-1J-2010D01*
G37*
G36*
G01X664986D02*
X661786D01*
G02Y877186I0J2010D01*
G01X664987D01*
G02X664986Y873166I-1J-2010D01*
G37*
G36*
G01X652388D02*
X649188D01*
G02Y877186I0J2010D01*
G01X652389D01*
G02X652388Y873166I-1J-2010D01*
G37*
G36*
G01X630340D02*
X627140D01*
G02Y877186I0J2010D01*
G01X630341D01*
G02X630340Y873166I-1J-2010D01*
G37*
G36*
G01X617742D02*
X614542D01*
G02Y877186I0J2010D01*
G01X617743D01*
G02X617742Y873166I-1J-2010D01*
G37*
G36*
G01X605144D02*
X601944D01*
G02Y877186I0J2010D01*
G01X605145D01*
G02X605144Y873166I-1J-2010D01*
G37*
G36*
G01X592545D02*
X589345D01*
G02Y877186I0J2010D01*
G01X592546D01*
G02X592545Y873166I-1J-2010D01*
G37*
G36*
G01X579947D02*
X576747D01*
G02Y877186I0J2010D01*
G01X579948D01*
G02X579947Y873166I-1J-2010D01*
G37*
G36*
G01X567348D02*
X564148D01*
G02Y877186I0J2010D01*
G01X567349D01*
G02X567348Y873166I-1J-2010D01*
G37*
G36*
G01X554750D02*
X551550D01*
G02Y877186I0J2010D01*
G01X554751D01*
G02X554750Y873166I-1J-2010D01*
G37*
G36*
G01X542151D02*
X538951D01*
G02Y877186I0J2010D01*
G01X542152D01*
G02X542151Y873166I-1J-2010D01*
G37*
G36*
G01X420891D02*
X417691D01*
G02Y877186I0J2010D01*
G01X420892D01*
G02X420891Y873166I-1J-2010D01*
G37*
G36*
G01X408292D02*
X405092D01*
G02Y877186I0J2010D01*
G01X408293D01*
G02X408292Y873166I-1J-2010D01*
G37*
G36*
G01X395694D02*
X392494D01*
G02Y877186I0J2010D01*
G01X395695D01*
G02X395694Y873166I-1J-2010D01*
G37*
G36*
G01X383096D02*
X379896D01*
G02Y877186I0J2010D01*
G01X383097D01*
G02X383096Y873166I-1J-2010D01*
G37*
G36*
G01X361048D02*
X357848D01*
G02Y877186I0J2010D01*
G01X361049D01*
G02X361048Y873166I-1J-2010D01*
G37*
G36*
G01X348450D02*
X345250D01*
G02Y877186I0J2010D01*
G01X348451D01*
G02X348450Y873166I-1J-2010D01*
G37*
G36*
G01X335851D02*
X332651D01*
G02Y877186I0J2010D01*
G01X335852D01*
G02X335851Y873166I-1J-2010D01*
G37*
G36*
G01X323253D02*
X320053D01*
G02Y877186I0J2010D01*
G01X323254D01*
G02X323253Y873166I-1J-2010D01*
G37*
G36*
G01X272859D02*
X269659D01*
G02Y877186I0J2010D01*
G01X272860D01*
G02X272859Y873166I-1J-2010D01*
G37*
G36*
G01X260261D02*
X257061D01*
G02Y877186I0J2010D01*
G01X260262D01*
G02X260261Y873166I-1J-2010D01*
G37*
G36*
G01X238213D02*
X235013D01*
G02Y877186I0J2010D01*
G01X238214D01*
G02X238213Y873166I-1J-2010D01*
G37*
G36*
G01X225615D02*
X222415D01*
G02Y877186I0J2010D01*
G01X225616D01*
G02X225615Y873166I-1J-2010D01*
G37*
G36*
G01X213017D02*
X209817D01*
G02Y877186I0J2010D01*
G01X213018D01*
G02X213017Y873166I-1J-2010D01*
G37*
G36*
G01X200418Y869666D02*
X197218D01*
G02Y873686I0J2010D01*
G01X200419D01*
G02X200418Y869666I-1J-2010D01*
G37*
G36*
G01X702400Y866790D02*
X699200D01*
G02Y870810I0J2010D01*
G01X702401D01*
G02X702400Y866790I-1J-2010D01*
G37*
G36*
G01X1198937Y865191D02*
Y865181D01*
X1195737Y865281D01*
Y865283D01*
X1195561Y865304D01*
G02X1195863Y869309I238J1996D01*
G01Y869319D01*
X1199062Y869219D01*
X1199071Y869210D01*
X1199145Y869205D01*
G02X1198937Y865191I-145J-2005D01*
G37*
G36*
G01X285500Y864190D02*
X282300D01*
G02Y868210I0J2010D01*
G01X285501D01*
G02X285500Y864190I-1J-2010D01*
G37*
G36*
G01X310955Y863666D02*
X307755D01*
G02Y867686I0J2010D01*
G01X310956D01*
G02X310955Y863666I-1J-2010D01*
G37*
G36*
G01X1350025Y828291D02*
X1346825D01*
G02Y832311I0J2010D01*
G01X1350026D01*
G02X1350025Y828291I-1J-2010D01*
G37*
G36*
G01X1337427D02*
X1334227D01*
G02Y832311I0J2010D01*
G01X1337428D01*
G02X1337427Y828291I-1J-2010D01*
G37*
G36*
G01X1324829D02*
X1321628D01*
G02X1321629Y832311I1J2010D01*
G01X1324829D01*
G02Y828291I0J-2010D01*
G37*
G36*
G01X1312231D02*
X1309030D01*
G02X1309031Y832311I1J2010D01*
G01X1312231D01*
G02Y828291I0J-2010D01*
G37*
G36*
G01X1287033D02*
X1283832D01*
G02X1283833Y832311I1J2010D01*
G01X1287033D01*
G02Y828291I0J-2010D01*
G37*
G36*
G01X1274435D02*
X1271234D01*
G02X1271235Y832311I1J2010D01*
G01X1274435D01*
G02Y828291I0J-2010D01*
G37*
G36*
G01X1261837D02*
X1258636D01*
G02X1258637Y832311I1J2010D01*
G01X1261837D01*
G02Y828291I0J-2010D01*
G37*
G36*
G01X1249239D02*
X1246038D01*
G02X1246039Y832311I1J2010D01*
G01X1249239D01*
G02Y828291I0J-2010D01*
G37*
G36*
G01X1236640D02*
X1233439D01*
G02X1233440Y832311I1J2010D01*
G01X1236640D01*
G02Y828291I0J-2010D01*
G37*
G36*
G01X1224042D02*
X1220842D01*
G02Y832311I0J2010D01*
G01X1224043D01*
G02X1224042Y828291I-1J-2010D01*
G37*
G36*
G01X1192545D02*
X1189344D01*
G02X1189345Y832311I1J2010D01*
G01X1192545D01*
G02Y828291I0J-2010D01*
G37*
G36*
G01X1179947D02*
X1176746D01*
G02X1176747Y832311I1J2010D01*
G01X1179947D01*
G02Y828291I0J-2010D01*
G37*
G36*
G01X1157899D02*
X1154698D01*
G02X1154699Y832311I1J2010D01*
G01X1157899D01*
G02Y828291I0J-2010D01*
G37*
G36*
G01X1145301D02*
X1142100D01*
G02X1142101Y832311I1J2010D01*
G01X1145301D01*
G02Y828291I0J-2010D01*
G37*
G36*
G01X1132703D02*
X1129503D01*
G02Y832311I0J2010D01*
G01X1132704D01*
G02X1132703Y828291I-1J-2010D01*
G37*
G36*
G01X1120104D02*
X1116903D01*
G02X1116904Y832311I1J2010D01*
G01X1120104D01*
G02Y828291I0J-2010D01*
G37*
G36*
G01X1107506D02*
X1104305D01*
G02X1104306Y832311I1J2010D01*
G01X1107506D01*
G02Y828291I0J-2010D01*
G37*
G36*
G01X1094907D02*
X1091706D01*
G02X1091707Y832311I1J2010D01*
G01X1094907D01*
G02Y828291I0J-2010D01*
G37*
G36*
G01X1082309D02*
X1079108D01*
G02X1079109Y832311I1J2010D01*
G01X1082309D01*
G02Y828291I0J-2010D01*
G37*
G36*
G01X1069711D02*
X1066510D01*
G02X1066511Y832311I1J2010D01*
G01X1069711D01*
G02Y828291I0J-2010D01*
G37*
G36*
G01X1057112D02*
X1053911D01*
G02X1053912Y832311I1J2010D01*
G01X1057112D01*
G02Y828291I0J-2010D01*
G37*
G36*
G01X1044514D02*
X1041313D01*
G02X1041314Y832311I1J2010D01*
G01X1044514D01*
G02Y828291I0J-2010D01*
G37*
G36*
G01X853962D02*
X850761D01*
G02X850762Y832311I1J2010D01*
G01X853962D01*
G02Y828291I0J-2010D01*
G37*
G36*
G01X841364D02*
X838163D01*
G02X838164Y832311I1J2010D01*
G01X841364D01*
G02Y828291I0J-2010D01*
G37*
G36*
G01X816167D02*
X812966D01*
G02X812967Y832311I1J2010D01*
G01X816167D01*
G02Y828291I0J-2010D01*
G37*
G36*
G01X803569D02*
X800368D01*
G02X800369Y832311I1J2010D01*
G01X803569D01*
G02Y828291I0J-2010D01*
G37*
G36*
G01X790970D02*
X787769D01*
G02X787770Y832311I1J2010D01*
G01X790970D01*
G02Y828291I0J-2010D01*
G37*
G36*
G01X778372D02*
X775171D01*
G02X775172Y832311I1J2010D01*
G01X778372D01*
G02Y828291I0J-2010D01*
G37*
G36*
G01X765774D02*
X762573D01*
G02X762574Y832311I1J2010D01*
G01X765774D01*
G02Y828291I0J-2010D01*
G37*
G36*
G01X753175D02*
X749974D01*
G02X749975Y832311I1J2010D01*
G01X753175D01*
G02Y828291I0J-2010D01*
G37*
G36*
G01X740577D02*
X737376D01*
G02X737377Y832311I1J2010D01*
G01X740577D01*
G02Y828291I0J-2010D01*
G37*
G36*
G01X727978D02*
X724777D01*
G02X724778Y832311I1J2010D01*
G01X727978D01*
G02Y828291I0J-2010D01*
G37*
G36*
G01X696482D02*
X693281D01*
G02X693282Y832311I1J2010D01*
G01X696482D01*
G02Y828291I0J-2010D01*
G37*
G36*
G01X683884D02*
X680683D01*
G02X680684Y832311I1J2010D01*
G01X683884D01*
G02Y828291I0J-2010D01*
G37*
G36*
G01X671285D02*
X668084D01*
G02X668085Y832311I1J2010D01*
G01X671285D01*
G02Y828291I0J-2010D01*
G37*
G36*
G01X658687D02*
X655486D01*
G02X655487Y832311I1J2010D01*
G01X658687D01*
G02Y828291I0J-2010D01*
G37*
G36*
G01X636640D02*
X633439D01*
G02X633440Y832311I1J2010D01*
G01X636640D01*
G02Y828291I0J-2010D01*
G37*
G36*
G01X624042D02*
X620841D01*
G02X620842Y832311I1J2010D01*
G01X624042D01*
G02Y828291I0J-2010D01*
G37*
G36*
G01X611443D02*
X608242D01*
G02X608243Y832311I1J2010D01*
G01X611443D01*
G02Y828291I0J-2010D01*
G37*
G36*
G01X598845D02*
X595644D01*
G02X595645Y832311I1J2010D01*
G01X598845D01*
G02Y828291I0J-2010D01*
G37*
G36*
G01X586246D02*
X583045D01*
G02X583046Y832311I1J2010D01*
G01X586246D01*
G02Y828291I0J-2010D01*
G37*
G36*
G01X573648D02*
X570447D01*
G02X570448Y832311I1J2010D01*
G01X573648D01*
G02Y828291I0J-2010D01*
G37*
G36*
G01X561050D02*
X557849D01*
G02X557850Y832311I1J2010D01*
G01X561050D01*
G02Y828291I0J-2010D01*
G37*
G36*
G01X548451D02*
X545250D01*
G02X545251Y832311I1J2010D01*
G01X548451D01*
G02Y828291I0J-2010D01*
G37*
G36*
G01X427191D02*
X423990D01*
G02X423991Y832311I1J2010D01*
G01X427191D01*
G02Y828291I0J-2010D01*
G37*
G36*
G01X414593D02*
X411392D01*
G02X411393Y832311I1J2010D01*
G01X414593D01*
G02Y828291I0J-2010D01*
G37*
G36*
G01X401994D02*
X398794D01*
G02Y832311I0J2010D01*
G01X401995D01*
G02X401994Y828291I-1J-2010D01*
G37*
G36*
G01X389396D02*
X386195D01*
G02X386196Y832311I1J2010D01*
G01X389396D01*
G02Y828291I0J-2010D01*
G37*
G36*
G01X367348D02*
X364147D01*
G02X364148Y832311I1J2010D01*
G01X367348D01*
G02Y828291I0J-2010D01*
G37*
G36*
G01X354750D02*
X351549D01*
G02X351550Y832311I1J2010D01*
G01X354750D01*
G02Y828291I0J-2010D01*
G37*
G36*
G01X342151D02*
X338950D01*
G02X338951Y832311I1J2010D01*
G01X342151D01*
G02Y828291I0J-2010D01*
G37*
G36*
G01X329553D02*
X326352D01*
G02X326353Y832311I1J2010D01*
G01X329553D01*
G02Y828291I0J-2010D01*
G37*
G36*
G01X316954D02*
X313753D01*
G02X313754Y832311I1J2010D01*
G01X316954D01*
G02Y828291I0J-2010D01*
G37*
G36*
G01X279159D02*
X275958D01*
G02X275959Y832311I1J2010D01*
G01X279159D01*
G02Y828291I0J-2010D01*
G37*
G36*
G01X266561D02*
X263360D01*
G02X263361Y832311I1J2010D01*
G01X266561D01*
G02Y828291I0J-2010D01*
G37*
G36*
G01X253962D02*
X250761D01*
G02X250762Y832311I1J2010D01*
G01X253962D01*
G02Y828291I0J-2010D01*
G37*
G36*
G01X231915D02*
X228714D01*
G02X228715Y832311I1J2010D01*
G01X231915D01*
G02Y828291I0J-2010D01*
G37*
G36*
G01X219317D02*
X216117D01*
G02Y832311I0J2010D01*
G01X219318D01*
G02X219317Y828291I-1J-2010D01*
G37*
G36*
G01X206718D02*
X203517D01*
G02X203518Y832311I1J2010D01*
G01X206718D01*
G02Y828291I0J-2010D01*
G37*
G36*
G01X194120D02*
X190919D01*
G02X190920Y832311I1J2010D01*
G01X194120D01*
G02Y828291I0J-2010D01*
G37*
G36*
G01X200620Y819691D02*
X197419D01*
G02X197420Y823711I1J2010D01*
G01X200620D01*
G02Y819691I0J-2010D01*
G37*
G36*
G01X370875Y720990D02*
X367675D01*
G02Y725010I0J2010D01*
G01X370876D01*
G02X370875Y720990I-1J-2010D01*
G37*
G36*
G01X58811Y727750D02*
X58250Y727189D01*
Y722311D01*
X64750Y715811D01*
Y705189D01*
X60311Y700750D01*
X31689D01*
X27250Y705189D01*
Y714811D01*
X30189Y717750D01*
X35689D01*
X40189Y722250D01*
X47689D01*
X48250Y722811D01*
Y726189D01*
X45750Y728689D01*
Y735689D01*
X43189Y738250D01*
X39189D01*
X33689Y743750D01*
X23689D01*
X20750Y746689D01*
Y770311D01*
X35189Y784750D01*
X89811D01*
X97750Y776811D01*
Y738689D01*
X92811Y733750D01*
X75689D01*
X72189Y737250D01*
X62311D01*
X61750Y736689D01*
Y729189D01*
X60311Y727750D01*
X58811D01*
G37*
G36*
G01X593750Y369511D02*
X594689Y370450D01*
X610911D01*
X612150Y369211D01*
Y354289D01*
X610611Y352750D01*
X595389D01*
X593750Y354389D01*
Y369511D01*
G37*
G36*
G01X85500Y327000D02*
X80500D01*
G02X80100Y327400I0J400D01*
G01Y332600D01*
G02X80500Y333000I400J0D01*
G01X85500D01*
G02X85900Y332600I0J-400D01*
G01Y327400D01*
G02X85500Y327000I-400J0D01*
G37*
G36*
G01X29011Y361650D02*
X31111Y359550D01*
X44511D01*
X48550Y355511D01*
Y326589D01*
X45811Y323850D01*
X24189D01*
X22150Y325889D01*
Y359711D01*
X24089Y361650D01*
X29011D01*
G37*
G36*
G01X21750Y293011D02*
X23289Y294550D01*
X35911D01*
X41050Y289411D01*
Y270289D01*
X35311Y264550D01*
X23189D01*
X21750Y265989D01*
Y293011D01*
G37*
G36*
G01X802200Y193990D02*
X798999D01*
G02X799000Y198010I1J2010D01*
G01X802200D01*
G02Y193990I0J-2010D01*
G37*
G36*
G01X1225348Y135950D02*
X1222148D01*
G02Y139970I0J2010D01*
G01X1225349D01*
G02X1225348Y135950I-1J-2010D01*
G37*
G36*
G01X1190835Y135889D02*
X1187635D01*
G02Y139909I0J2010D01*
G01X1190836D01*
G02X1190835Y135889I-1J-2010D01*
G37*
G36*
G01X1242900Y135841D02*
X1239700D01*
G02Y139861I0J2010D01*
G01X1242901D01*
G02X1242900Y135841I-1J-2010D01*
G37*
G36*
G01X1141900D02*
X1138700D01*
G02Y139861I0J2010D01*
G01X1141901D01*
G02X1141900Y135841I-1J-2010D01*
G37*
G36*
G01X718790Y114150D02*
Y117350D01*
G02X722810I2010J0D01*
G01Y114149D01*
G02X718790Y114150I-2010J1D01*
G37*
G36*
G01X568342Y92882D02*
X568235Y93048D01*
X568234Y93047D01*
X565281Y98559D01*
X565284Y98561D01*
X565213Y98720D01*
G02X569627Y100887I2245J1005D01*
G01X569721Y100710D01*
X569729Y100715D01*
X572588Y95380D01*
X572583Y95375D01*
X572642Y95249D01*
G02X568342Y92882I-2231J-1036D01*
G37*
G36*
G01X1170704D02*
X1170597Y93048D01*
X1170596Y93047D01*
X1167643Y98559D01*
X1167646Y98561D01*
X1167575Y98720D01*
G02X1171989Y100887I2245J1005D01*
G01X1172083Y100710D01*
X1172091Y100715D01*
X1174950Y95380D01*
X1174945Y95375D01*
X1175004Y95249D01*
G02X1170704Y92882I-2231J-1036D01*
G37*
G36*
G01X1222870D02*
X1222763Y93048D01*
X1222762Y93047D01*
X1219809Y98558D01*
X1219814Y98563D01*
X1219755Y98689D01*
G02X1224155Y100887I2231J1036D01*
G01X1224249Y100710D01*
X1224257Y100715D01*
X1227116Y95379D01*
X1227113Y95377D01*
X1227184Y95218D01*
G02X1222870Y92882I-2246J-1004D01*
G37*
G36*
G01X1188421D02*
X1188314Y93048D01*
X1188313Y93047D01*
X1185360Y98558D01*
X1185365Y98563D01*
X1185306Y98689D01*
G02X1189706Y100887I2231J1036D01*
G01X1189800Y100710D01*
X1189808Y100715D01*
X1192667Y95379D01*
X1192664Y95377D01*
X1192735Y95218D01*
G02X1188421Y92882I-2246J-1004D01*
G37*
G36*
G01X672673D02*
X672566Y93048D01*
X672565Y93047D01*
X669612Y98558D01*
X669617Y98563D01*
X669558Y98689D01*
G02X673958Y100887I2231J1036D01*
G01X674052Y100710D01*
X674060Y100715D01*
X676919Y95379D01*
X676916Y95377D01*
X676987Y95218D01*
G02X672673Y92882I-2246J-1004D01*
G37*
G36*
G01X663815D02*
X663708Y93048D01*
X663707Y93047D01*
X660754Y98558D01*
X660759Y98563D01*
X660700Y98689D01*
G02X665100Y100887I2231J1036D01*
G01X665194Y100710D01*
X665202Y100715D01*
X668061Y95379D01*
X668058Y95377D01*
X668129Y95218D01*
G02X663815Y92882I-2246J-1004D01*
G37*
G36*
G01X629366D02*
X629259Y93048D01*
X629258Y93047D01*
X626305Y98558D01*
X626310Y98563D01*
X626251Y98689D01*
G02X630651Y100887I2231J1036D01*
G01X630745Y100710D01*
X630753Y100715D01*
X633612Y95379D01*
X633609Y95377D01*
X633680Y95218D01*
G02X629366Y92882I-2246J-1004D01*
G37*
G36*
G01X620508D02*
X620401Y93048D01*
X620400Y93047D01*
X617447Y98558D01*
X617452Y98563D01*
X617393Y98689D01*
G02X621793Y100887I2231J1036D01*
G01X621887Y100710D01*
X621895Y100715D01*
X624754Y95379D01*
X624751Y95377D01*
X624822Y95218D01*
G02X620508Y92882I-2246J-1004D01*
G37*
G36*
G01X586059D02*
X585952Y93048D01*
X585951Y93047D01*
X582998Y98558D01*
X583003Y98563D01*
X582944Y98689D01*
G02X587344Y100887I2231J1036D01*
G01X587438Y100710D01*
X587446Y100715D01*
X590305Y95379D01*
X590302Y95377D01*
X590373Y95218D01*
G02X586059Y92882I-2246J-1004D01*
G37*
G36*
G01X542752D02*
X542645Y93048D01*
X542644Y93047D01*
X539691Y98558D01*
X539696Y98563D01*
X539637Y98689D01*
G02X544037Y100887I2231J1036D01*
G01X544131Y100710D01*
X544139Y100715D01*
X546998Y95379D01*
X546995Y95377D01*
X547066Y95218D01*
G02X542752Y92882I-2246J-1004D01*
G37*
G36*
G01X533793Y93052D02*
X530857Y98534D01*
X530856Y98535D01*
G02X535179Y100886I2154J1190D01*
G01X538131Y95374D01*
G02X533793Y93052I-2169J-1161D01*
G37*
G36*
G01X525035Y92882D02*
X524928Y93048D01*
X524927Y93047D01*
X521974Y98558D01*
X521979Y98563D01*
X521920Y98689D01*
G02X526320Y100887I2231J1036D01*
G01X526414Y100710D01*
X526422Y100715D01*
X529281Y95379D01*
X529278Y95377D01*
X529349Y95218D01*
G02X525035Y92882I-2246J-1004D01*
G37*
G36*
G01X1257218Y93052D02*
X1254266Y98564D01*
G02X1256412Y102185I2169J1161D01*
G02X1258604Y100886I23J-2460D01*
G01X1261540Y95404D01*
X1261541Y95403D01*
G02X1257218Y93052I-2154J-1190D01*
G37*
G36*
G01X1213911D02*
X1210959Y98564D01*
G02X1215297Y100886I2169J1161D01*
G01X1218233Y95404D01*
X1218234Y95403D01*
G02X1213911Y93052I-2154J-1190D01*
G37*
G36*
G01X654856D02*
X651904Y98564D01*
G02X656242Y100886I2169J1161D01*
G01X659178Y95404D01*
X659179Y95403D01*
G02X654856Y93052I-2154J-1190D01*
G37*
G36*
G01X611549D02*
X608597Y98564D01*
G02X612935Y100886I2169J1161D01*
G01X615871Y95404D01*
X615872Y95403D01*
G02X611549Y93052I-2154J-1190D01*
G37*
G36*
G01X718790Y93150D02*
Y96351D01*
G02X722810Y96350I2010J-1D01*
G01Y93150D01*
G02X718790I-2010J0D01*
G37*
G36*
G01X672673Y77921D02*
X672566Y78087D01*
X672565Y78086D01*
X669612Y83598D01*
X669615Y83600D01*
X669544Y83759D01*
G02X673958Y85926I2245J1005D01*
G01X674052Y85749D01*
X674060Y85754D01*
X676919Y80419D01*
X676914Y80414D01*
X676973Y80288D01*
G02X672673Y77921I-2231J-1036D01*
G37*
G36*
G01X663815D02*
X663708Y78087D01*
X663707Y78086D01*
X660754Y83598D01*
X660757Y83600D01*
X660686Y83759D01*
G02X665100Y85926I2245J1005D01*
G01X665194Y85749D01*
X665202Y85754D01*
X668061Y80419D01*
X668056Y80414D01*
X668115Y80288D01*
G02X663815Y77921I-2231J-1036D01*
G37*
G36*
G01X586059D02*
X585952Y78087D01*
X585951Y78086D01*
X582998Y83598D01*
X583001Y83600D01*
X582930Y83759D01*
G02X587344Y85926I2245J1005D01*
G01X587438Y85749D01*
X587446Y85754D01*
X590305Y80419D01*
X590300Y80414D01*
X590359Y80288D01*
G02X586059Y77921I-2231J-1036D01*
G37*
G36*
G01X1188421D02*
X1188314Y78087D01*
X1188313Y78086D01*
X1185360Y83598D01*
X1185363Y83600D01*
X1185292Y83759D01*
G02X1189706Y85926I2245J1005D01*
G01X1189800Y85749D01*
X1189808Y85754D01*
X1192667Y80419D01*
X1192662Y80414D01*
X1192721Y80288D01*
G02X1188421Y77921I-2231J-1036D01*
G37*
G36*
G01X1145114D02*
X1145007Y78087D01*
X1145006Y78086D01*
X1142053Y83597D01*
X1142058Y83602D01*
X1141999Y83728D01*
G02X1146399Y85926I2231J1036D01*
G01X1146493Y85749D01*
X1146501Y85754D01*
X1149360Y80418D01*
X1149357Y80416D01*
X1149428Y80257D01*
G02X1145114Y77921I-2246J-1004D01*
G37*
G36*
G01X533793Y78091D02*
X530857Y83573D01*
X530856Y83574D01*
G02X535179Y85925I2154J1190D01*
G01X538131Y80413D01*
G02X533793Y78091I-2169J-1161D01*
G37*
G36*
G01X1179462D02*
X1176510Y83603D01*
G02X1180848Y85925I2169J1161D01*
G01X1183784Y80443D01*
X1183785Y80442D01*
G02X1179462Y78091I-2154J-1190D01*
G37*
G36*
G01X1101339Y70669D02*
X1101315Y72263D01*
X1101290Y73869D01*
G02X1105310Y73931I2010J31D01*
G01X1105359Y70732D01*
G02X1101339Y70669I-2010J-32D01*
G37*
G36*
G01X1170704Y48000D02*
X1170597Y48166D01*
X1170596Y48165D01*
X1167643Y53676D01*
X1167648Y53681D01*
X1167589Y53807D01*
G02X1171989Y56005I2231J1036D01*
G01X1172083Y55828D01*
X1172091Y55833D01*
X1174950Y50497D01*
X1174947Y50495D01*
X1175018Y50336D01*
G02X1170704Y48000I-2246J-1004D01*
G37*
G36*
G01X568342D02*
X568235Y48166D01*
X568234Y48165D01*
X565281Y53676D01*
X565286Y53681D01*
X565227Y53807D01*
G02X569627Y56005I2231J1036D01*
G01X569721Y55828D01*
X569729Y55833D01*
X572588Y50497D01*
X572585Y50495D01*
X572656Y50336D01*
G02X568342Y48000I-2246J-1004D01*
G37*
G36*
G01X1319928Y833701D02*
Y838901D01*
G02X1320429Y839402I501J0D01*
G01X1326029D01*
G02X1326530Y838901I0J-501D01*
G01Y833701D01*
G02X1326029Y833200I-501J0D01*
G01X1320429D01*
G02X1319928Y833701I0J501D01*
G37*
G36*
G01X1332526D02*
Y838901D01*
G02X1333027Y839402I501J0D01*
G01X1338627D01*
G02X1339128Y838901I0J-501D01*
G01Y833701D01*
G02X1338627Y833200I-501J0D01*
G01X1333027D01*
G02X1332526Y833701I0J501D01*
G37*
G36*
G01X1345124D02*
Y838901D01*
G02X1345625Y839402I501J0D01*
G01X1351225D01*
G02X1351726Y838901I0J-501D01*
G01Y833701D01*
G02X1351225Y833200I-501J0D01*
G01X1345625D01*
G02X1345124Y833701I0J501D01*
G37*
G36*
G01X1282132D02*
Y838901D01*
G02X1282633Y839402I501J0D01*
G01X1288233D01*
G02X1288734Y838901I0J-501D01*
G01Y833701D01*
G02X1288233Y833200I-501J0D01*
G01X1282633D01*
G02X1282132Y833701I0J501D01*
G37*
G36*
G01X1307830Y839402D02*
X1313432D01*
G02X1313932Y838901I-1J-501D01*
G01Y833701D01*
G02X1313430Y833200I-502J1D01*
G01X1307828D01*
G02X1307328Y833701I1J501D01*
G01Y838901D01*
G02X1307830Y839402I502J-1D01*
G37*
G36*
G01X1292817Y139490D02*
X1296018D01*
G02X1296017Y135466I-1J-2012D01*
G01X1292817D01*
G02Y139490I0J2012D01*
G37*
G36*
G01X1283343Y143592D02*
X1286544D01*
G02X1286543Y139570I-1J-2011D01*
G01X1283343D01*
G02Y143592I0J2011D01*
G37*
G36*
G01X1281842Y129130D02*
Y134332D01*
G02X1282343Y134832I501J-1D01*
G01X1287443D01*
G02X1287944Y134330I-1J-502D01*
G01Y129128D01*
G02X1287443Y128628I-501J1D01*
G01X1282343D01*
G02X1281842Y129130I1J502D01*
G37*
G36*
G01X1291262Y129000D02*
Y134202D01*
G02X1291763Y134702I501J-1D01*
G01X1296863D01*
G02X1297364Y134200I-1J-502D01*
G01Y128998D01*
G02X1296863Y128498I-501J1D01*
G01X1291763D01*
G02X1291262Y129000I1J502D01*
G37*
G36*
G01X1256936Y833701D02*
Y838901D01*
G02X1257437Y839402I501J0D01*
G01X1263037D01*
G02X1263538Y838901I0J-501D01*
G01Y833701D01*
G02X1263037Y833200I-501J0D01*
G01X1257437D01*
G02X1256936Y833701I0J501D01*
G37*
G36*
G01X1269534D02*
Y838901D01*
G02X1270035Y839402I501J0D01*
G01X1275635D01*
G02X1276136Y838901I0J-501D01*
G01Y833701D01*
G02X1275635Y833200I-501J0D01*
G01X1270035D01*
G02X1269534Y833701I0J501D01*
G37*
G36*
G01X1261944Y143758D02*
X1258743D01*
G02X1258744Y147782I1J2012D01*
G01X1261944D01*
G02Y143758I0J-2012D01*
G37*
G36*
G01X1277265Y135662D02*
X1274064D01*
G02X1274065Y139684I1J2011D01*
G01X1277265D01*
G02Y135662I0J-2011D01*
G37*
G36*
G01X1272564Y129222D02*
Y134424D01*
G02X1273065Y134924I501J-1D01*
G01X1278165D01*
G02X1278666Y134422I-1J-502D01*
G01Y129220D01*
G02X1278165Y128720I-501J1D01*
G01X1273065D01*
G02X1272564Y129222I1J502D01*
G37*
G36*
G01X1257744Y135020D02*
X1262846D01*
G02X1263346Y134519I-1J-501D01*
G01Y129319D01*
G02X1262844Y128818I-502J1D01*
G01X1257742D01*
G02X1257242Y129319I1J501D01*
G01Y134519D01*
G02X1257744Y135020I502J-1D01*
G37*
G36*
G01X1266177Y92880D02*
X1266070Y93046D01*
X1266068Y93045D01*
X1263114Y98558D01*
X1263119Y98563D01*
X1263060Y98690D01*
G02X1267463Y100888I2233J1035D01*
G01X1267557Y100712D01*
X1267565Y100716D01*
X1270425Y95378D01*
X1270422Y95377D01*
X1270493Y95218D01*
G02X1266177Y92880I-2248J-1004D01*
G37*
G36*
G01Y77919D02*
X1266070Y78085D01*
X1266068Y78084D01*
X1263114Y83599D01*
X1263117Y83600D01*
X1263046Y83759D01*
G02X1267463Y85927I2247J1006D01*
G01X1267557Y85751D01*
X1267565Y85755D01*
X1270425Y80419D01*
X1270420Y80414D01*
X1270479Y80287D01*
G02X1266177Y77919I-2234J-1034D01*
G37*
G36*
G01X1275035D02*
X1274928Y78085D01*
X1274926Y78084D01*
X1271972Y83599D01*
X1271975Y83600D01*
X1271904Y83759D01*
G02X1276321Y85927I2247J1006D01*
G01X1276415Y85751D01*
X1276423Y85755D01*
X1279283Y80419D01*
X1279278Y80414D01*
X1279337Y80287D01*
G02X1275035Y77919I-2234J-1034D01*
G37*
G36*
G01Y92880D02*
X1274928Y93046D01*
X1274926Y93045D01*
X1271972Y98558D01*
X1271977Y98563D01*
X1271918Y98690D01*
G02X1276321Y100888I2233J1035D01*
G01X1276415Y100712D01*
X1276423Y100716D01*
X1279283Y95378D01*
X1279280Y95377D01*
X1279351Y95218D01*
G02X1275035Y92880I-2248J-1004D01*
G37*
G36*
G01X1258605Y56005D02*
X1261557Y50493D01*
G02X1257217Y48169I-2170J-1162D01*
G01X1254281Y53651D01*
X1254280Y53652D01*
G02X1258605Y56005I2155J1191D01*
G37*
G36*
G01X1275035Y47998D02*
X1274928Y48164D01*
X1274926Y48163D01*
X1271972Y53676D01*
X1271977Y53681D01*
X1271918Y53808D01*
G02X1276321Y56006I2233J1035D01*
G01X1276415Y55830D01*
X1276423Y55834D01*
X1279283Y50496D01*
X1279280Y50495D01*
X1279351Y50336D01*
G02X1275035Y47998I-2248J-1004D01*
G37*
G36*
G01X1266177D02*
X1266070Y48164D01*
X1266068Y48163D01*
X1263114Y53676D01*
X1263119Y53681D01*
X1263060Y53808D01*
G02X1267463Y56006I2233J1035D01*
G01X1267557Y55830D01*
X1267565Y55834D01*
X1270425Y50496D01*
X1270422Y50495D01*
X1270493Y50336D01*
G02X1266177Y47998I-2248J-1004D01*
G37*
G36*
G01X1275030Y62966D02*
X1274929Y63124D01*
X1274926Y63123D01*
X1271972Y68636D01*
X1271977Y68641D01*
X1271918Y68768D01*
G02X1276320Y70967I2233J1035D01*
G01X1276414Y70791D01*
X1276423Y70796D01*
X1279283Y65458D01*
X1279280Y65457D01*
X1279354Y65290D01*
G02X1275030Y62966I-2250J-999D01*
G37*
G36*
G01X1266172D02*
X1266071Y63124D01*
X1266068Y63123D01*
X1263114Y68636D01*
X1263119Y68641D01*
X1263060Y68768D01*
G02X1267462Y70967I2233J1035D01*
G01X1267556Y70791D01*
X1267565Y70796D01*
X1270425Y65458D01*
X1270422Y65457D01*
X1270496Y65290D01*
G02X1266172Y62966I-2250J-999D01*
G37*
G36*
G01X1219140Y833701D02*
Y838901D01*
G02X1219641Y839402I501J0D01*
G01X1225241D01*
G02X1225742Y838901I0J-501D01*
G01Y833701D01*
G02X1225241Y833200I-501J0D01*
G01X1219641D01*
G02X1219140Y833701I0J501D01*
G37*
G36*
G01X1232240Y839402D02*
X1237842D01*
G02X1238342Y838901I-1J-501D01*
G01Y833701D01*
G02X1237840Y833200I-502J1D01*
G01X1232238D01*
G02X1231738Y833701I1J501D01*
G01Y838901D01*
G02X1232240Y839402I502J-1D01*
G37*
G36*
G01X1244838D02*
X1250440D01*
G02X1250940Y838901I-1J-501D01*
G01Y833701D01*
G02X1250438Y833200I-502J1D01*
G01X1244836D01*
G02X1244336Y833701I1J501D01*
G01Y838901D01*
G02X1244838Y839402I502J-1D01*
G37*
G36*
G01X1234209Y140452D02*
X1231008D01*
G02X1231009Y144474I1J2011D01*
G01X1234209D01*
G02Y140452I0J-2011D01*
G37*
G36*
G01X1221148Y135210D02*
X1226250D01*
G02X1226750Y134709I-1J-501D01*
G01Y129509D01*
G02X1226248Y129008I-502J1D01*
G01X1221146D01*
G02X1220646Y129509I1J501D01*
G01Y134709D01*
G02X1221148Y135210I502J-1D01*
G37*
G36*
G01X1229508Y129512D02*
Y134714D01*
G02X1230009Y135214I501J-1D01*
G01X1235109D01*
G02X1235610Y134712I-1J-502D01*
G01Y129510D01*
G02X1235109Y129010I-501J1D01*
G01X1230009D01*
G02X1229508Y129512I1J502D01*
G37*
G36*
G01X1238198Y129400D02*
Y134600D01*
G02X1238700Y135102I502J0D01*
G01X1243800D01*
G02X1244302Y134600I0J-502D01*
G01Y129400D01*
G02X1243800Y128898I-502J0D01*
G01X1238700D01*
G02X1238198Y129400I0J502D01*
G37*
G36*
G01X1222870Y77919D02*
X1222763Y78085D01*
X1222761Y78084D01*
X1219807Y83599D01*
X1219810Y83600D01*
X1219739Y83759D01*
G02X1224156Y85927I2247J1006D01*
G01X1224250Y85751D01*
X1224258Y85755D01*
X1227118Y80419D01*
X1227113Y80414D01*
X1227172Y80287D01*
G02X1222870Y77919I-2234J-1034D01*
G37*
G36*
G01X1231728Y92880D02*
X1231621Y93046D01*
X1231619Y93045D01*
X1228665Y98558D01*
X1228670Y98563D01*
X1228611Y98690D01*
G02X1233014Y100888I2233J1035D01*
G01X1233108Y100712D01*
X1233116Y100716D01*
X1235976Y95378D01*
X1235973Y95377D01*
X1236044Y95218D01*
G02X1231728Y92880I-2248J-1004D01*
G37*
G36*
G01Y77919D02*
X1231621Y78085D01*
X1231619Y78084D01*
X1228665Y83599D01*
X1228668Y83600D01*
X1228597Y83759D01*
G02X1233014Y85927I2247J1006D01*
G01X1233108Y85751D01*
X1233116Y85755D01*
X1235976Y80419D01*
X1235971Y80414D01*
X1236030Y80287D01*
G02X1231728Y77919I-2234J-1034D01*
G37*
G36*
G01Y47998D02*
X1231621Y48164D01*
X1231619Y48163D01*
X1228665Y53676D01*
X1228670Y53681D01*
X1228611Y53808D01*
G02X1233014Y56006I2233J1035D01*
G01X1233108Y55830D01*
X1233116Y55834D01*
X1235976Y50496D01*
X1235973Y50495D01*
X1236044Y50336D01*
G02X1231728Y47998I-2248J-1004D01*
G37*
G36*
G01X1222870D02*
X1222763Y48164D01*
X1222761Y48163D01*
X1219807Y53676D01*
X1219812Y53681D01*
X1219753Y53808D01*
G02X1224156Y56006I2233J1035D01*
G01X1224250Y55830D01*
X1224258Y55834D01*
X1227118Y50496D01*
X1227115Y50495D01*
X1227186Y50336D01*
G02X1222870Y47998I-2248J-1004D01*
G37*
G36*
G01X1231723Y62966D02*
X1231622Y63124D01*
X1231619Y63123D01*
X1228665Y68636D01*
X1228670Y68641D01*
X1228611Y68768D01*
G02X1233013Y70967I2233J1035D01*
G01X1233107Y70791D01*
X1233116Y70796D01*
X1235976Y65458D01*
X1235973Y65457D01*
X1236047Y65290D01*
G02X1231723Y62966I-2250J-999D01*
G37*
G36*
G01X1222865D02*
X1222764Y63124D01*
X1222761Y63123D01*
X1219807Y68636D01*
X1219812Y68641D01*
X1219753Y68768D01*
G02X1224155Y70967I2233J1035D01*
G01X1224249Y70791D01*
X1224258Y70796D01*
X1227118Y65458D01*
X1227115Y65457D01*
X1227189Y65290D01*
G02X1222865Y62966I-2250J-999D01*
G37*
G36*
G01X1187644Y833701D02*
Y838901D01*
G02X1188145Y839402I501J0D01*
G01X1193745D01*
G02X1194246Y838901I0J-501D01*
G01Y833701D01*
G02X1193745Y833200I-501J0D01*
G01X1188145D01*
G02X1187644Y833701I0J501D01*
G37*
G36*
G01X1203791Y158742D02*
X1206992D01*
G02X1206991Y154718I-1J-2012D01*
G01X1203791D01*
G02Y158742I0J2012D01*
G37*
G36*
G01X1196200Y144862D02*
X1199401D01*
G02X1199400Y140840I-1J-2011D01*
G01X1196200D01*
G02Y144862I0J2011D01*
G37*
G36*
G01X1177360Y129527D02*
Y134727D01*
G02X1177861Y135228I501J0D01*
G01X1182961D01*
G02X1183462Y134727I0J-501D01*
G01Y129527D01*
G02X1182961Y129026I-501J0D01*
G01X1177861D01*
G02X1177360Y129527I0J501D01*
G37*
G36*
G01X1186134Y129448D02*
Y134650D01*
G02X1186635Y135150I501J-1D01*
G01X1191735D01*
G02X1192236Y134648I-1J-502D01*
G01Y129446D01*
G02X1191735Y128946I-501J1D01*
G01X1186635D01*
G02X1186134Y129448I1J502D01*
G37*
G36*
G01X1194698Y129400D02*
Y134600D01*
G02X1195200Y135102I502J0D01*
G01X1200300D01*
G02X1200802Y134600I0J-502D01*
G01Y129400D01*
G02X1200300Y128898I-502J0D01*
G01X1195200D01*
G02X1194698Y129400I0J502D01*
G37*
G36*
G01X1203170Y129347D02*
Y134547D01*
G02X1203671Y135048I501J0D01*
G01X1208771D01*
G02X1209272Y134547I0J-501D01*
G01Y129347D01*
G02X1208771Y128846I-501J0D01*
G01X1203671D01*
G02X1203170Y129347I0J501D01*
G37*
G36*
G01X1215298Y56005D02*
X1218250Y50493D01*
G02X1213910Y48169I-2170J-1162D01*
G01X1210974Y53651D01*
X1210973Y53652D01*
G02X1215298Y56005I2155J1191D01*
G37*
G36*
G01X1188421Y47998D02*
X1188314Y48164D01*
X1188312Y48163D01*
X1185358Y53676D01*
X1185363Y53681D01*
X1185304Y53808D01*
G02X1189707Y56006I2233J1035D01*
G01X1189801Y55830D01*
X1189809Y55834D01*
X1192669Y50496D01*
X1192666Y50495D01*
X1192737Y50336D01*
G02X1188421Y47998I-2248J-1004D01*
G37*
G36*
G01X1188416Y62966D02*
X1188315Y63124D01*
X1188312Y63123D01*
X1185358Y68636D01*
X1185363Y68641D01*
X1185304Y68768D01*
G02X1189706Y70967I2233J1035D01*
G01X1189800Y70791D01*
X1189809Y70796D01*
X1192669Y65458D01*
X1192666Y65457D01*
X1192740Y65290D01*
G02X1188416Y62966I-2250J-999D01*
G37*
G36*
G01X1152998Y833701D02*
Y838901D01*
G02X1153499Y839402I501J0D01*
G01X1159099D01*
G02X1159600Y838901I0J-501D01*
G01Y833701D01*
G02X1159099Y833200I-501J0D01*
G01X1153499D01*
G02X1152998Y833701I0J501D01*
G37*
G36*
G01X1175046D02*
Y838901D01*
G02X1175547Y839402I501J0D01*
G01X1181147D01*
G02X1181648Y838901I0J-501D01*
G01Y833701D01*
G02X1181147Y833200I-501J0D01*
G01X1175547D01*
G02X1175046Y833701I0J501D01*
G37*
G36*
G01X1182061Y140466D02*
X1178860D01*
G02X1178861Y144490I1J2012D01*
G01X1182061D01*
G02Y140466I0J-2012D01*
G37*
G36*
G01X1161307Y136494D02*
X1158106D01*
G02X1158107Y140516I1J2011D01*
G01X1161307D01*
G02Y136494I0J-2011D01*
G37*
G36*
G01X1180849Y100887D02*
X1183801Y95375D01*
G02X1179461Y93051I-2170J-1162D01*
G01X1176525Y98533D01*
X1176524Y98534D01*
G02X1180849Y100887I2155J1191D01*
G37*
G36*
G01Y56005D02*
X1183801Y50493D01*
G02X1179461Y48169I-2170J-1162D01*
G01X1176525Y53651D01*
X1176524Y53652D01*
G02X1180849Y56005I2155J1191D01*
G37*
G36*
G01X1179562Y62959D02*
X1179455Y63125D01*
X1179453Y63124D01*
X1176500Y68636D01*
X1176505Y68641D01*
X1176446Y68768D01*
G02X1180849Y70966I2233J1035D01*
G01X1180943Y70790D01*
X1180951Y70794D01*
X1183810Y65457D01*
X1183807Y65456D01*
X1183878Y65297D01*
G02X1179562Y62959I-2248J-1004D01*
G37*
G36*
G01X1115704Y839402D02*
X1121306D01*
G02X1121806Y838901I-1J-501D01*
G01Y833701D01*
G02X1121304Y833200I-502J1D01*
G01X1115702D01*
G02X1115202Y833701I1J501D01*
G01Y838901D01*
G02X1115704Y839402I502J-1D01*
G37*
G36*
G01X1127802Y833701D02*
Y838901D01*
G02X1128303Y839402I501J0D01*
G01X1133903D01*
G02X1134404Y838901I0J-501D01*
G01Y833701D01*
G02X1133903Y833200I-501J0D01*
G01X1128303D01*
G02X1127802Y833701I0J501D01*
G37*
G36*
G01X1140400D02*
Y838901D01*
G02X1140901Y839402I501J0D01*
G01X1146501D01*
G02X1147002Y838901I0J-501D01*
G01Y833701D01*
G02X1146501Y833200I-501J0D01*
G01X1140901D01*
G02X1140400Y833701I0J501D01*
G37*
G36*
G01X1119990Y130124D02*
Y133325D01*
G02X1124012Y133324I2011J-1D01*
G01Y130124D01*
G02X1119990I-2011J0D01*
G37*
G36*
G01X1124798Y129000D02*
Y134100D01*
G02X1125300Y134602I502J0D01*
G01X1130500D01*
G02X1131002Y134100I0J-502D01*
G01Y129000D01*
G02X1130500Y128498I-502J0D01*
G01X1125300D01*
G02X1124798Y129000I0J502D01*
G37*
G36*
G01X1137198Y129400D02*
Y134600D01*
G02X1137700Y135102I502J0D01*
G01X1142800D01*
G02X1143302Y134600I0J-502D01*
G01Y129400D01*
G02X1142800Y128898I-502J0D01*
G01X1137700D01*
G02X1137198Y129400I0J502D01*
G37*
G36*
G01X1127397Y92880D02*
X1127290Y93046D01*
X1127288Y93045D01*
X1124334Y98558D01*
X1124339Y98563D01*
X1124280Y98690D01*
G02X1128683Y100888I2233J1035D01*
G01X1128777Y100712D01*
X1128785Y100716D01*
X1131645Y95378D01*
X1131642Y95377D01*
X1131713Y95218D01*
G02X1127397Y92880I-2248J-1004D01*
G37*
G36*
G01X1137542Y100887D02*
X1140494Y95375D01*
G02X1136154Y93051I-2170J-1162D01*
G01X1133218Y98533D01*
X1133217Y98534D01*
G02X1137542Y100887I2155J1191D01*
G37*
G36*
G01X1111088Y81902D02*
X1111198Y82050D01*
X1111197Y82052D01*
X1113341Y84432D01*
X1113343Y84430D01*
X1113475Y84553D01*
G02X1116337Y81733I1367J-1475D01*
G01X1116203Y81585D01*
X1116211Y81578D01*
X1114203Y79348D01*
X1114192D01*
X1114133Y79288D01*
G02X1111088Y81902I-1432J1412D01*
G37*
G36*
G01X1145114Y92880D02*
X1145007Y93046D01*
X1145005Y93045D01*
X1142051Y98558D01*
X1142056Y98563D01*
X1141997Y98690D01*
G02X1146400Y100888I2233J1035D01*
G01X1146494Y100712D01*
X1146502Y100716D01*
X1149362Y95378D01*
X1149359Y95377D01*
X1149430Y95218D01*
G02X1145114Y92880I-2248J-1004D01*
G37*
G36*
G01X1137542Y85926D02*
X1140494Y80414D01*
G02X1136154Y78090I-2170J-1162D01*
G01X1133218Y83572D01*
X1133217Y83573D01*
G02X1137542Y85926I2155J1191D01*
G37*
G36*
G01X1127397Y47998D02*
X1127290Y48164D01*
X1127288Y48163D01*
X1124334Y53678D01*
X1124337Y53679D01*
X1124266Y53838D01*
G02X1128683Y56006I2247J1006D01*
G01X1128777Y55830D01*
X1128785Y55834D01*
X1131645Y50498D01*
X1131640Y50493D01*
X1131699Y50366D01*
G02X1127397Y47998I-2234J-1034D01*
G37*
G36*
G01X1145114D02*
X1145007Y48164D01*
X1145005Y48163D01*
X1142051Y53678D01*
X1142054Y53679D01*
X1141983Y53838D01*
G02X1146400Y56006I2247J1006D01*
G01X1146494Y55830D01*
X1146502Y55834D01*
X1149362Y50498D01*
X1149357Y50493D01*
X1149416Y50366D01*
G02X1145114Y47998I-2234J-1034D01*
G37*
G36*
G01X1137542Y56005D02*
X1140478Y50523D01*
X1140479Y50522D01*
G02X1136154Y48169I-2155J-1191D01*
G01X1133202Y53681D01*
G02X1137542Y56005I2170J1162D01*
G37*
G36*
G01X1145109Y62966D02*
X1145008Y63124D01*
X1145005Y63123D01*
X1142051Y68636D01*
X1142056Y68641D01*
X1141997Y68768D01*
G02X1146399Y70967I2233J1035D01*
G01X1146493Y70791D01*
X1146502Y70796D01*
X1149362Y65458D01*
X1149359Y65457D01*
X1149433Y65290D01*
G02X1145109Y62966I-2250J-999D01*
G37*
G36*
G01X1136255Y62959D02*
X1136148Y63125D01*
X1136146Y63124D01*
X1133193Y68636D01*
X1133198Y68641D01*
X1133139Y68768D01*
G02X1137542Y70966I2233J1035D01*
G01X1137636Y70790D01*
X1137644Y70794D01*
X1140503Y65457D01*
X1140500Y65456D01*
X1140571Y65297D01*
G02X1136255Y62959I-2248J-1004D01*
G37*
G36*
G01X1077408Y833701D02*
Y838901D01*
G02X1077909Y839402I501J0D01*
G01X1083509D01*
G02X1084010Y838901I0J-501D01*
G01Y833701D01*
G02X1083509Y833200I-501J0D01*
G01X1077909D01*
G02X1077408Y833701I0J501D01*
G37*
G36*
G01X1090006D02*
Y838901D01*
G02X1090507Y839402I501J0D01*
G01X1096107D01*
G02X1096608Y838901I0J-501D01*
G01Y833701D01*
G02X1096107Y833200I-501J0D01*
G01X1090507D01*
G02X1090006Y833701I0J501D01*
G37*
G36*
G01X1103106Y839402D02*
X1108708D01*
G02X1109208Y838901I-1J-501D01*
G01Y833701D01*
G02X1108706Y833200I-502J1D01*
G01X1103104D01*
G02X1102604Y833701I1J501D01*
G01Y838901D01*
G02X1103106Y839402I502J-1D01*
G37*
G36*
G01X1052712D02*
X1058314D01*
G02X1058814Y838901I-1J-501D01*
G01Y833701D01*
G02X1058312Y833200I-502J1D01*
G01X1052710D01*
G02X1052210Y833701I1J501D01*
G01Y838901D01*
G02X1052712Y839402I502J-1D01*
G37*
G36*
G01X1064810Y833701D02*
Y838901D01*
G02X1065311Y839402I501J0D01*
G01X1070911D01*
G02X1071412Y838901I0J-501D01*
G01Y833701D01*
G02X1070911Y833200I-501J0D01*
G01X1065311D01*
G02X1064810Y833701I0J501D01*
G37*
G36*
G01X1069124Y57175D02*
Y60376D01*
G02X1073146Y60375I2011J-1D01*
G01Y57175D01*
G02X1069124I-2011J0D01*
G37*
G36*
G01X1059012Y57700D02*
Y54499D01*
G02X1054988Y54500I-2012J1D01*
G01Y57700D01*
G02X1059012I2012J0D01*
G37*
G36*
G01X1075398Y49200D02*
Y54300D01*
G02X1075900Y54802I502J0D01*
G01X1081100D01*
G02X1081602Y54300I0J-502D01*
G01Y49200D01*
G02X1081100Y48698I-502J0D01*
G01X1075900D01*
G02X1075398Y49200I0J502D01*
G37*
G36*
G01Y56200D02*
Y61300D01*
G02X1075900Y61802I502J0D01*
G01X1081100D01*
G02X1081602Y61300I0J-502D01*
G01Y56200D01*
G02X1081100Y55698I-502J0D01*
G01X1075900D01*
G02X1075398Y56200I0J502D01*
G37*
G36*
G01X1063212Y24088D02*
Y20887D01*
G02X1059188Y20888I-2012J1D01*
G01Y24088D01*
G02X1063212I2012J0D01*
G37*
G36*
G01X1067712Y36088D02*
Y32887D01*
G02X1063688Y32888I-2012J1D01*
G01Y36088D01*
G02X1067712I2012J0D01*
G37*
G36*
G01X1040114Y839402D02*
X1045716D01*
G02X1046216Y838901I-1J-501D01*
G01Y833701D01*
G02X1045714Y833200I-502J1D01*
G01X1040112D01*
G02X1039612Y833701I1J501D01*
G01Y838901D01*
G02X1040114Y839402I502J-1D01*
G37*
G36*
G01X849562D02*
X855164D01*
G02X855664Y838901I-1J-501D01*
G01Y833701D01*
G02X855162Y833200I-502J1D01*
G01X849560D01*
G02X849060Y833701I1J501D01*
G01Y838901D01*
G02X849562Y839402I502J-1D01*
G37*
G36*
G01X811266Y833701D02*
Y838901D01*
G02X811767Y839402I501J0D01*
G01X817367D01*
G02X817868Y838901I0J-501D01*
G01Y833701D01*
G02X817367Y833200I-501J0D01*
G01X811767D01*
G02X811266Y833701I0J501D01*
G37*
G36*
G01X836964Y839402D02*
X842566D01*
G02X843066Y838901I-1J-501D01*
G01Y833701D01*
G02X842564Y833200I-502J1D01*
G01X836962D01*
G02X836462Y833701I1J501D01*
G01Y838901D01*
G02X836964Y839402I502J-1D01*
G37*
G36*
G01X839586Y156938D02*
X834386D01*
G02X833884Y157440I0J502D01*
G01Y162540D01*
G02X834386Y163042I502J0D01*
G01X839586D01*
G02X840088Y162540I0J-502D01*
G01Y157440D01*
G02X839586Y156938I-502J0D01*
G37*
G36*
G01X773972Y839402D02*
X779574D01*
G02X780074Y838901I-1J-501D01*
G01Y833701D01*
G02X779572Y833200I-502J1D01*
G01X773970D01*
G02X773470Y833701I1J501D01*
G01Y838901D01*
G02X773972Y839402I502J-1D01*
G37*
G36*
G01X786570D02*
X792172D01*
G02X792672Y838901I-1J-501D01*
G01Y833701D01*
G02X792170Y833200I-502J1D01*
G01X786568D01*
G02X786068Y833701I1J501D01*
G01Y838901D01*
G02X786570Y839402I502J-1D01*
G37*
G36*
G01X798668Y833701D02*
Y838901D01*
G02X799169Y839402I501J0D01*
G01X804769D01*
G02X805270Y838901I0J-501D01*
G01Y833701D01*
G02X804769Y833200I-501J0D01*
G01X799169D01*
G02X798668Y833701I0J501D01*
G37*
G36*
G01X781218Y183890D02*
Y179489D01*
G02X776396Y179490I-2411J1D01*
G01Y183890D01*
G02X781218I2411J0D01*
G37*
G36*
G01X787614Y198215D02*
X792013Y198189D01*
G02X791986Y193367I-14J-2411D01*
G01X787586Y193393D01*
G02X787614Y198215I14J2411D01*
G37*
G36*
G01X790348Y176043D02*
Y180444D01*
G02X795172Y180443I2412J-1D01*
G01Y176043D01*
G02X790348I-2412J0D01*
G37*
G36*
G01X748776Y839402D02*
X754378D01*
G02X754878Y838901I-1J-501D01*
G01Y833701D01*
G02X754376Y833200I-502J1D01*
G01X748774D01*
G02X748274Y833701I1J501D01*
G01Y838901D01*
G02X748776Y839402I502J-1D01*
G37*
G36*
G01X761374D02*
X766976D01*
G02X767476Y838901I-1J-501D01*
G01Y833701D01*
G02X766974Y833200I-502J1D01*
G01X761372D01*
G02X760872Y833701I1J501D01*
G01Y838901D01*
G02X761374Y839402I502J-1D01*
G37*
G36*
G01X723078Y833701D02*
Y838901D01*
G02X723579Y839402I501J0D01*
G01X729179D01*
G02X729680Y838901I0J-501D01*
G01Y833701D01*
G02X729179Y833200I-501J0D01*
G01X723579D01*
G02X723078Y833701I0J501D01*
G37*
G36*
G01X735676D02*
Y838901D01*
G02X736177Y839402I501J0D01*
G01X741777D01*
G02X742278Y838901I0J-501D01*
G01Y833701D01*
G02X741777Y833200I-501J0D01*
G01X736177D01*
G02X735676Y833701I0J501D01*
G37*
G36*
G01X711898Y113200D02*
Y118300D01*
G02X712400Y118802I502J0D01*
G01X717600D01*
G02X718102Y118300I0J-502D01*
G01Y113200D01*
G02X717600Y112698I-502J0D01*
G01X712400D01*
G02X711898Y113200I0J502D01*
G37*
G36*
G01Y77200D02*
Y82300D01*
G02X712400Y82802I502J0D01*
G01X717600D01*
G02X718102Y82300I0J-502D01*
G01Y77200D01*
G02X717600Y76698I-502J0D01*
G01X712400D01*
G02X711898Y77200I0J502D01*
G37*
G36*
G01Y84200D02*
Y89300D01*
G02X712400Y89802I502J0D01*
G01X717600D01*
G02X718102Y89300I0J-502D01*
G01Y84200D01*
G02X717600Y83698I-502J0D01*
G01X712400D01*
G02X711898Y84200I0J502D01*
G37*
G36*
G01Y92200D02*
Y97300D01*
G02X712400Y97802I502J0D01*
G01X717600D01*
G02X718102Y97300I0J-502D01*
G01Y92200D01*
G02X717600Y91698I-502J0D01*
G01X712400D01*
G02X711898Y92200I0J502D01*
G37*
G36*
G01Y101200D02*
Y106300D01*
G02X712400Y106802I502J0D01*
G01X717600D01*
G02X718102Y106300I0J-502D01*
G01Y101200D01*
G02X717600Y100698I-502J0D01*
G01X712400D01*
G02X711898Y101200I0J502D01*
G37*
G36*
G01X722812Y81350D02*
Y78149D01*
G02X718788Y78150I-2012J1D01*
G01Y81350D01*
G02X722812I2012J0D01*
G37*
G36*
G01X734512Y101621D02*
Y98420D01*
G02X730488Y98421I-2012J1D01*
G01Y101621D01*
G02X734512I2012J0D01*
G37*
G36*
G01X722812Y105350D02*
Y102149D01*
G02X718788Y102150I-2012J1D01*
G01Y105350D01*
G02X722812I2012J0D01*
G37*
G36*
G01X728620Y49251D02*
Y46050D01*
G02X724598Y46051I-2011J1D01*
G01Y49251D01*
G02X728620I2011J0D01*
G37*
G36*
G01X722955Y35106D02*
X726156D01*
G02X726155Y31084I-1J-2011D01*
G01X722955D01*
G02Y35106I0J2011D01*
G37*
G36*
G01X679484Y839402D02*
X685086D01*
G02X685586Y838901I-1J-501D01*
G01Y833701D01*
G02X685084Y833200I-502J1D01*
G01X679482D01*
G02X678982Y833701I1J501D01*
G01Y838901D01*
G02X679484Y839402I502J-1D01*
G37*
G36*
G01X692082D02*
X697684D01*
G02X698184Y838901I-1J-501D01*
G01Y833701D01*
G02X697682Y833200I-502J1D01*
G01X692080D01*
G02X691580Y833701I1J501D01*
G01Y838901D01*
G02X692082Y839402I502J-1D01*
G37*
G36*
G01X683600Y376706D02*
X680099D01*
G02X680100Y380730I1J2012D01*
G01X683600D01*
G02Y376706I0J-2012D01*
G37*
G36*
G01X653786Y833701D02*
Y838901D01*
G02X654287Y839402I501J0D01*
G01X659887D01*
G02X660388Y838901I0J-501D01*
G01Y833701D01*
G02X659887Y833200I-501J0D01*
G01X654287D01*
G02X653786Y833701I0J501D01*
G37*
G36*
G01X666384D02*
Y838901D01*
G02X666885Y839402I501J0D01*
G01X672485D01*
G02X672986Y838901I0J-501D01*
G01Y833701D01*
G02X672485Y833200I-501J0D01*
G01X666885D01*
G02X666384Y833701I0J501D01*
G37*
G36*
G01X662256Y352200D02*
Y348999D01*
G02X658232Y349000I-2012J1D01*
G01Y352200D01*
G02X662256I2012J0D01*
G37*
G36*
G01X640550Y323512D02*
X643751D01*
G02X643750Y319488I-1J-2012D01*
G01X640550D01*
G02Y323512I0J2012D01*
G37*
G36*
G01X641198Y129400D02*
Y134600D01*
G02X641700Y135102I502J0D01*
G01X646800D01*
G02X647302Y134600I0J-502D01*
G01Y129400D01*
G02X646800Y128898I-502J0D01*
G01X641700D01*
G02X641198Y129400I0J502D01*
G37*
G36*
G01X656243Y56005D02*
X659195Y50493D01*
G02X654855Y48169I-2170J-1162D01*
G01X651919Y53651D01*
X651918Y53652D01*
G02X656243Y56005I2155J1191D01*
G37*
G36*
G01X663815Y47998D02*
X663708Y48164D01*
X663706Y48163D01*
X660752Y53676D01*
X660757Y53681D01*
X660698Y53808D01*
G02X665101Y56006I2233J1035D01*
G01X665195Y55830D01*
X665203Y55834D01*
X668063Y50496D01*
X668060Y50495D01*
X668131Y50336D01*
G02X663815Y47998I-2248J-1004D01*
G37*
G36*
G01X663810Y62966D02*
X663709Y63124D01*
X663706Y63123D01*
X660752Y68636D01*
X660757Y68641D01*
X660698Y68768D01*
G02X665100Y70967I2233J1035D01*
G01X665194Y70791D01*
X665203Y70796D01*
X668063Y65458D01*
X668060Y65457D01*
X668134Y65290D01*
G02X663810Y62966I-2250J-999D01*
G37*
G36*
G01X672668D02*
X672567Y63124D01*
X672564Y63123D01*
X669610Y68636D01*
X669615Y68641D01*
X669556Y68768D01*
G02X673958Y70967I2233J1035D01*
G01X674052Y70791D01*
X674061Y70796D01*
X676921Y65458D01*
X676918Y65457D01*
X676992Y65290D01*
G02X672668Y62966I-2250J-999D01*
G37*
G36*
G01X672673Y47998D02*
X672566Y48164D01*
X672564Y48163D01*
X669610Y53676D01*
X669615Y53681D01*
X669556Y53808D01*
G02X673959Y56006I2233J1035D01*
G01X674053Y55830D01*
X674061Y55834D01*
X676921Y50496D01*
X676918Y50495D01*
X676989Y50336D01*
G02X672673Y47998I-2248J-1004D01*
G37*
G36*
G01X606542Y833701D02*
Y838901D01*
G02X607043Y839402I501J0D01*
G01X612643D01*
G02X613144Y838901I0J-501D01*
G01Y833701D01*
G02X612643Y833200I-501J0D01*
G01X607043D01*
G02X606542Y833701I0J501D01*
G37*
G36*
G01X619642Y839402D02*
X625244D01*
G02X625744Y838901I-1J-501D01*
G01Y833701D01*
G02X625242Y833200I-502J1D01*
G01X619640D01*
G02X619140Y833701I1J501D01*
G01Y838901D01*
G02X619642Y839402I502J-1D01*
G37*
G36*
G01X632240D02*
X637842D01*
G02X638342Y838901I-1J-501D01*
G01Y833701D01*
G02X637840Y833200I-502J1D01*
G01X632238D01*
G02X631738Y833701I1J501D01*
G01Y838901D01*
G02X632240Y839402I502J-1D01*
G37*
G36*
G01X640700Y332798D02*
X639298D01*
G02X639210Y332808I1J402D01*
G01X639201Y332798D01*
X635300D01*
G02X634898Y333200I0J402D01*
G01Y338000D01*
G02X635300Y338402I402J0D01*
G01X640700D01*
G02X641102Y338000I0J-402D01*
G01Y333200D01*
G02X640700Y332798I-402J0D01*
G37*
G36*
G01X636950Y151662D02*
X640151D01*
G02X640150Y147638I-1J-2012D01*
G01X636950D01*
G02Y151662I0J2012D01*
G37*
G36*
G01X638150Y135868D02*
X634949D01*
G02X634950Y139892I1J2012D01*
G01X638150D01*
G02Y135868I0J-2012D01*
G37*
G36*
G01X627826D02*
X624625D01*
G02X624626Y139892I1J2012D01*
G01X627826D01*
G02Y135868I0J-2012D01*
G37*
G36*
G01X633198Y129400D02*
Y134600D01*
G02X633700Y135102I502J0D01*
G01X638800D01*
G02X639302Y134600I0J-502D01*
G01Y129400D01*
G02X638800Y128898I-502J0D01*
G01X633700D01*
G02X633198Y129400I0J502D01*
G37*
G36*
G01X622874D02*
Y134600D01*
G02X623376Y135102I502J0D01*
G01X628476D01*
G02X628978Y134600I0J-502D01*
G01Y129400D01*
G02X628476Y128898I-502J0D01*
G01X623376D01*
G02X622874Y129400I0J502D01*
G37*
G36*
G01X629366Y77919D02*
X629259Y78085D01*
X629257Y78084D01*
X626303Y83599D01*
X626306Y83600D01*
X626235Y83759D01*
G02X630652Y85927I2247J1006D01*
G01X630746Y85751D01*
X630754Y85755D01*
X633614Y80419D01*
X633609Y80414D01*
X633668Y80287D01*
G02X629366Y77919I-2234J-1034D01*
G37*
G36*
G01X612936Y56005D02*
X615888Y50493D01*
G02X611548Y48169I-2170J-1162D01*
G01X608612Y53651D01*
X608611Y53652D01*
G02X612936Y56005I2155J1191D01*
G37*
G36*
G01X629366Y47998D02*
X629259Y48164D01*
X629257Y48163D01*
X626303Y53676D01*
X626308Y53681D01*
X626249Y53808D01*
G02X630652Y56006I2233J1035D01*
G01X630746Y55830D01*
X630754Y55834D01*
X633614Y50496D01*
X633611Y50495D01*
X633682Y50336D01*
G02X629366Y47998I-2248J-1004D01*
G37*
G36*
G01X629361Y62966D02*
X629260Y63124D01*
X629257Y63123D01*
X626303Y68636D01*
X626308Y68641D01*
X626249Y68768D01*
G02X630651Y70967I2233J1035D01*
G01X630745Y70791D01*
X630754Y70796D01*
X633614Y65458D01*
X633611Y65457D01*
X633685Y65290D01*
G02X629361Y62966I-2250J-999D01*
G37*
G36*
G01X620503D02*
X620402Y63124D01*
X620399Y63123D01*
X617445Y68636D01*
X617450Y68641D01*
X617391Y68768D01*
G02X621793Y70967I2233J1035D01*
G01X621887Y70791D01*
X621896Y70796D01*
X624756Y65458D01*
X624753Y65457D01*
X624827Y65290D01*
G02X620503Y62966I-2250J-999D01*
G37*
G36*
G01X620508Y47998D02*
X620401Y48164D01*
X620399Y48163D01*
X617445Y53676D01*
X617450Y53681D01*
X617391Y53808D01*
G02X621794Y56006I2233J1035D01*
G01X621888Y55830D01*
X621896Y55834D01*
X624756Y50496D01*
X624753Y50495D01*
X624824Y50336D01*
G02X620508Y47998I-2248J-1004D01*
G37*
G36*
G01X581846Y839402D02*
X587448D01*
G02X587948Y838901I-1J-501D01*
G01Y833701D01*
G02X587446Y833200I-502J1D01*
G01X581844D01*
G02X581344Y833701I1J501D01*
G01Y838901D01*
G02X581846Y839402I502J-1D01*
G37*
G36*
G01X593944Y833701D02*
Y838901D01*
G02X594445Y839402I501J0D01*
G01X600045D01*
G02X600546Y838901I0J-501D01*
G01Y833701D01*
G02X600045Y833200I-501J0D01*
G01X594445D01*
G02X593944Y833701I0J501D01*
G37*
G36*
G01X594150Y151962D02*
X597351D01*
G02X597350Y147938I-1J-2012D01*
G01X594150D01*
G02Y151962I0J2012D01*
G37*
G36*
G01X601250Y139792D02*
X604451D01*
G02X604450Y135768I-1J-2012D01*
G01X601250D01*
G02Y139792I0J2012D01*
G37*
G36*
G01X584650Y139812D02*
X587851D01*
G02X587850Y135788I-1J-2012D01*
G01X584650D01*
G02Y139812I0J2012D01*
G37*
G36*
G01X577650Y135768D02*
X574449D01*
G02X574450Y139792I1J2012D01*
G01X577650D01*
G02Y135768I0J-2012D01*
G37*
G36*
G01X599498Y129300D02*
Y134500D01*
G02X600000Y135002I502J0D01*
G01X605100D01*
G02X605602Y134500I0J-502D01*
G01Y129300D01*
G02X605100Y128798I-502J0D01*
G01X600000D01*
G02X599498Y129300I0J502D01*
G37*
G36*
G01X572998Y129380D02*
Y134580D01*
G02X573500Y135082I502J0D01*
G01X578600D01*
G02X579102Y134580I0J-502D01*
G01Y129380D01*
G02X578600Y128878I-502J0D01*
G01X573500D01*
G02X572998Y129380I0J502D01*
G37*
G36*
G01X583198Y129400D02*
Y134600D01*
G02X583700Y135102I502J0D01*
G01X588800D01*
G02X589302Y134600I0J-502D01*
G01Y129400D01*
G02X588800Y128898I-502J0D01*
G01X583700D01*
G02X583198Y129400I0J502D01*
G37*
G36*
G01X591698D02*
Y134600D01*
G02X592200Y135102I502J0D01*
G01X597300D01*
G02X597802Y134600I0J-502D01*
G01Y129400D01*
G02X597300Y128898I-502J0D01*
G01X592200D01*
G02X591698Y129400I0J502D01*
G37*
G36*
G01X578487Y85926D02*
X581423Y80444D01*
X581424Y80443D01*
G02X577099Y78090I-2155J-1191D01*
G01X574147Y83602D01*
G02X578487Y85926I2170J1162D01*
G37*
G36*
G01X577099Y93051D02*
X574163Y98533D01*
X574162Y98534D01*
G02X578487Y100887I2155J1191D01*
G01X581439Y95375D01*
G02X577099Y93051I-2170J-1162D01*
G37*
G36*
G01X586054Y62966D02*
X585953Y63124D01*
X585950Y63123D01*
X582996Y68636D01*
X583001Y68641D01*
X582942Y68768D01*
G02X587344Y70967I2233J1035D01*
G01X587438Y70791D01*
X587447Y70796D01*
X590307Y65458D01*
X590304Y65457D01*
X590378Y65290D01*
G02X586054Y62966I-2250J-999D01*
G37*
G36*
G01X577200Y62959D02*
X577093Y63125D01*
X577091Y63124D01*
X574138Y68636D01*
X574143Y68641D01*
X574084Y68768D01*
G02X578487Y70966I2233J1035D01*
G01X578581Y70790D01*
X578589Y70794D01*
X581448Y65457D01*
X581445Y65456D01*
X581516Y65297D01*
G02X577200Y62959I-2248J-1004D01*
G37*
G36*
G01X586059Y47998D02*
X585952Y48164D01*
X585950Y48163D01*
X582996Y53676D01*
X583001Y53681D01*
X582942Y53808D01*
G02X587345Y56006I2233J1035D01*
G01X587439Y55830D01*
X587447Y55834D01*
X590307Y50496D01*
X590304Y50495D01*
X590375Y50336D01*
G02X586059Y47998I-2248J-1004D01*
G37*
G36*
G01X578487Y56005D02*
X581439Y50493D01*
G02X577099Y48169I-2170J-1162D01*
G01X574163Y53651D01*
X574162Y53652D01*
G02X578487Y56005I2155J1191D01*
G37*
G36*
G01X543550Y833701D02*
Y838901D01*
G02X544051Y839402I501J0D01*
G01X549651D01*
G02X550152Y838901I0J-501D01*
G01Y833701D01*
G02X549651Y833200I-501J0D01*
G01X544051D01*
G02X543550Y833701I0J501D01*
G37*
G36*
G01X556148D02*
Y838901D01*
G02X556649Y839402I501J0D01*
G01X562249D01*
G02X562750Y838901I0J-501D01*
G01Y833701D01*
G02X562249Y833200I-501J0D01*
G01X556649D01*
G02X556148Y833701I0J501D01*
G37*
G36*
G01X569248Y839402D02*
X574850D01*
G02X575350Y838901I-1J-501D01*
G01Y833701D01*
G02X574848Y833200I-502J1D01*
G01X569246D01*
G02X568746Y833701I1J501D01*
G01Y838901D01*
G02X569248Y839402I502J-1D01*
G37*
G36*
G01X548700Y150188D02*
X545499D01*
G02X545500Y154212I1J2012D01*
G01X548700D01*
G02Y150188I0J-2012D01*
G37*
G36*
G01X541600Y139780D02*
X544801D01*
G02X544800Y135758I-1J-2011D01*
G01X541600D01*
G02Y139780I0J2011D01*
G37*
G36*
G01X540108Y129410D02*
Y134610D01*
G02X540610Y135112I502J0D01*
G01X545710D01*
G02X546212Y134610I0J-502D01*
G01Y129410D01*
G02X545710Y128908I-502J0D01*
G01X540610D01*
G02X540108Y129410I0J502D01*
G37*
G36*
G01X542752Y47998D02*
X542645Y48164D01*
X542643Y48163D01*
X539689Y53678D01*
X539692Y53679D01*
X539621Y53838D01*
G02X544038Y56006I2247J1006D01*
G01X544132Y55830D01*
X544140Y55834D01*
X547000Y50498D01*
X546995Y50493D01*
X547054Y50366D01*
G02X542752Y47998I-2234J-1034D01*
G37*
G36*
G01X542747Y62966D02*
X542646Y63124D01*
X542643Y63123D01*
X539689Y68636D01*
X539694Y68641D01*
X539635Y68768D01*
G02X544037Y70967I2233J1035D01*
G01X544131Y70791D01*
X544140Y70796D01*
X547000Y65458D01*
X546997Y65457D01*
X547071Y65290D01*
G02X542747Y62966I-2250J-999D01*
G37*
G36*
G01X521098Y168200D02*
Y163799D01*
G02X516274Y163800I-2412J1D01*
G01Y168200D01*
G02X521098I2412J0D01*
G37*
G36*
G01X526977Y142720D02*
X530178D01*
G02X530177Y138696I-1J-2012D01*
G01X526977D01*
G02Y142720I0J2012D01*
G37*
G36*
G01X519300Y136860D02*
X516099D01*
G02X516100Y140882I1J2011D01*
G01X519300D01*
G02Y136860I0J-2011D01*
G37*
G36*
G01X531628Y129480D02*
Y134680D01*
G02X532130Y135182I502J0D01*
G01X537230D01*
G02X537732Y134680I0J-502D01*
G01Y129480D01*
G02X537230Y128978I-502J0D01*
G01X532130D01*
G02X531628Y129480I0J502D01*
G37*
G36*
G01X525035Y47998D02*
X524928Y48164D01*
X524926Y48163D01*
X521972Y53678D01*
X521975Y53679D01*
X521904Y53838D01*
G02X526321Y56006I2247J1006D01*
G01X526415Y55830D01*
X526423Y55834D01*
X529283Y50498D01*
X529278Y50493D01*
X529337Y50366D01*
G02X525035Y47998I-2234J-1034D01*
G37*
G36*
G01X535180Y56005D02*
X538116Y50523D01*
X538117Y50522D01*
G02X533792Y48169I-2155J-1191D01*
G01X530840Y53681D01*
G02X535180Y56005I2170J1162D01*
G37*
G36*
G01X533893Y62959D02*
X533786Y63125D01*
X533784Y63124D01*
X530831Y68636D01*
X530836Y68641D01*
X530777Y68768D01*
G02X535180Y70966I2233J1035D01*
G01X535274Y70790D01*
X535282Y70794D01*
X538141Y65457D01*
X538138Y65456D01*
X538209Y65297D01*
G02X533893Y62959I-2248J-1004D01*
G37*
G36*
G01X499136Y129850D02*
Y134650D01*
G02X499538Y135052I402J0D01*
G01X504948D01*
G02X505350Y134650I0J-402D01*
G01Y129850D01*
G02X504948Y129448I-402J0D01*
G01X499538D01*
G02X499136Y129850I0J402D01*
G37*
G36*
G01X409692Y833701D02*
Y838901D01*
G02X410193Y839402I501J0D01*
G01X415793D01*
G02X416294Y838901I0J-501D01*
G01Y833701D01*
G02X415793Y833200I-501J0D01*
G01X410193D01*
G02X409692Y833701I0J501D01*
G37*
G36*
G01X422290D02*
Y838901D01*
G02X422791Y839402I501J0D01*
G01X428391D01*
G02X428892Y838901I0J-501D01*
G01Y833701D01*
G02X428391Y833200I-501J0D01*
G01X422791D01*
G02X422290Y833701I0J501D01*
G37*
G36*
G01X406452Y323300D02*
Y318899D01*
G02X401628Y318900I-2412J1D01*
G01Y323300D01*
G02X406452I2412J0D01*
G37*
G36*
G01X401588Y142542D02*
Y146043D01*
G02X405612Y146042I2012J-1D01*
G01Y142542D01*
G02X401588I-2012J0D01*
G37*
G36*
G01X384996Y839402D02*
X390598D01*
G02X391098Y838901I-1J-501D01*
G01Y833701D01*
G02X390596Y833200I-502J1D01*
G01X384994D01*
G02X384494Y833701I1J501D01*
G01Y838901D01*
G02X384996Y839402I502J-1D01*
G37*
G36*
G01X397594D02*
X403196D01*
G02X403696Y838901I-1J-501D01*
G01Y833701D01*
G02X403194Y833200I-502J1D01*
G01X397592D01*
G02X397092Y833701I1J501D01*
G01Y838901D01*
G02X397594Y839402I502J-1D01*
G37*
G36*
G01X403312Y156715D02*
Y153214D01*
G02X399288Y153215I-2012J1D01*
G01Y156715D01*
G02X403312I2012J0D01*
G37*
G36*
G01X337250Y833701D02*
Y838901D01*
G02X337751Y839402I501J0D01*
G01X343351D01*
G02X343852Y838901I0J-501D01*
G01Y833701D01*
G02X343351Y833200I-501J0D01*
G01X337751D01*
G02X337250Y833701I0J501D01*
G37*
G36*
G01X350350Y839402D02*
X355952D01*
G02X356452Y838901I-1J-501D01*
G01Y833701D01*
G02X355950Y833200I-502J1D01*
G01X350348D01*
G02X349848Y833701I1J501D01*
G01Y838901D01*
G02X350350Y839402I502J-1D01*
G37*
G36*
G01X362948D02*
X368550D01*
G02X369050Y838901I-1J-501D01*
G01Y833701D01*
G02X368548Y833200I-502J1D01*
G01X362946D01*
G02X362446Y833701I1J501D01*
G01Y838901D01*
G02X362948Y839402I502J-1D01*
G37*
G36*
G01X360545Y730825D02*
X360662Y730965D01*
X360661Y730966D01*
X362924Y733230D01*
X362937D01*
X362995Y733283D01*
G02X365900Y730514I1360J-1482D01*
G01X365783Y730374D01*
X365784Y730373D01*
X363519Y728108D01*
X363518Y728109D01*
X363378Y727992D01*
G02X360545Y730825I-1287J1546D01*
G37*
G36*
G01X339640Y301534D02*
Y305035D01*
G02X343664Y305034I2012J-1D01*
G01Y301534D01*
G02X339640I-2012J0D01*
G37*
G36*
G01X370914Y40157D02*
G02X365945Y35188I-4969J0D01*
G01X356102D01*
G02X351132Y40157I0J4970D01*
G01Y71654D01*
G02X356102Y76624I4970J0D01*
G01X365945D01*
G02X370914Y71654I-1J-4970D01*
G01Y40157D01*
G37*
G36*
G01X312554Y839402D02*
X318156D01*
G02X318656Y838901I-1J-501D01*
G01Y833701D01*
G02X318154Y833200I-502J1D01*
G01X312552D01*
G02X312052Y833701I1J501D01*
G01Y838901D01*
G02X312554Y839402I502J-1D01*
G37*
G36*
G01X324652Y833701D02*
Y838901D01*
G02X325153Y839402I501J0D01*
G01X330753D01*
G02X331254Y838901I0J-501D01*
G01Y833701D01*
G02X330753Y833200I-501J0D01*
G01X325153D01*
G02X324652Y833701I0J501D01*
G37*
G36*
G01X274258D02*
Y838901D01*
G02X274759Y839402I501J0D01*
G01X280359D01*
G02X280860Y838901I0J-501D01*
G01Y833701D01*
G02X280359Y833200I-501J0D01*
G01X274759D01*
G02X274258Y833701I0J501D01*
G37*
G36*
G01X249562Y839402D02*
X255164D01*
G02X255664Y838901I-1J-501D01*
G01Y833701D01*
G02X255162Y833200I-502J1D01*
G01X249560D01*
G02X249060Y833701I1J501D01*
G01Y838901D01*
G02X249562Y839402I502J-1D01*
G37*
G36*
G01X261660Y833701D02*
Y838901D01*
G02X262161Y839402I501J0D01*
G01X267761D01*
G02X268262Y838901I0J-501D01*
G01Y833701D01*
G02X267761Y833200I-501J0D01*
G01X262161D01*
G02X261660Y833701I0J501D01*
G37*
G36*
G01X260407Y500662D02*
X257206D01*
G02X257207Y504686I1J2012D01*
G01X260407D01*
G02Y500662I0J-2012D01*
G37*
G36*
G01X202318Y839402D02*
X207920D01*
G02X208420Y838901I-1J-501D01*
G01Y833701D01*
G02X207918Y833200I-502J1D01*
G01X202316D01*
G02X201816Y833701I1J501D01*
G01Y838901D01*
G02X202318Y839402I502J-1D01*
G37*
G36*
G01X214416Y833701D02*
Y838901D01*
G02X214917Y839402I501J0D01*
G01X220517D01*
G02X221018Y838901I0J-501D01*
G01Y833701D01*
G02X220517Y833200I-501J0D01*
G01X214917D01*
G02X214416Y833701I0J501D01*
G37*
G36*
G01X227014D02*
Y838901D01*
G02X227515Y839402I501J0D01*
G01X233115D01*
G02X233616Y838901I0J-501D01*
G01Y833701D01*
G02X233115Y833200I-501J0D01*
G01X227515D01*
G02X227014Y833701I0J501D01*
G37*
G36*
G01X231750Y770688D02*
X228549D01*
G02X228550Y774712I1J2012D01*
G01X231750D01*
G02Y770688I0J-2012D01*
G37*
G36*
G01X213900Y500898D02*
X209100D01*
G02X208698Y501300I0J402D01*
G01Y506710D01*
G02X209100Y507112I402J0D01*
G01X213900D01*
G02X214302Y506710I0J-402D01*
G01Y501300D01*
G02X213900Y500898I-402J0D01*
G37*
G36*
G01X223872Y339875D02*
Y335474D01*
G02X219048Y335475I-2412J1D01*
G01Y339875D01*
G02X223872I2412J0D01*
G37*
G36*
G01X209866Y186480D02*
X206296D01*
G02X206297Y190504I1J2012D01*
G01X209866D01*
G02Y186480I0J-2012D01*
G37*
G36*
G01X189720Y839402D02*
X195322D01*
G02X195822Y838901I-1J-501D01*
G01Y833701D01*
G02X195320Y833200I-502J1D01*
G01X189718D01*
G02X189218Y833701I1J501D01*
G01Y838901D01*
G02X189720Y839402I502J-1D01*
G37*
G36*
G01X105282Y565740D02*
Y561339D01*
G02X100458Y561340I-2412J1D01*
G01Y565740D01*
G02X105282I2412J0D01*
G37*
G36*
G01X101190Y427417D02*
Y426017D01*
G02X100779Y425606I-411J0D01*
G01X99379D01*
G02X98968Y426017I0J411D01*
G01Y427417D01*
G02X99379Y427828I411J0D01*
G01X100779D01*
G02X101190Y427417I0J-411D01*
G37*
G36*
G01X98964Y430030D02*
Y431430D01*
G02X99376Y431842I412J0D01*
G01X100776D01*
G02X101188Y431430I0J-412D01*
G01Y430030D01*
G02X100776Y429618I-412J0D01*
G01X99376D01*
G02X98964Y430030I0J412D01*
G37*
G36*
G01X86350Y485150D02*
Y490250D01*
G02X86851Y490752I501J1D01*
G01X92051D01*
G02X92552Y490250I-1J-502D01*
G01Y485150D01*
G02X92051Y484648I-501J-1D01*
G01X86851D01*
G02X86350Y485150I1J502D01*
G37*
G36*
G01X96460Y497018D02*
X97260D01*
G02X97472Y496807I1J-211D01*
G01Y495807D01*
G02X97260Y495596I-212J1D01*
G01X96460D01*
G02X96248Y495807I-1J211D01*
G01Y496807D01*
G02X96460Y497018I212J-1D01*
G37*
G36*
G01Y494818D02*
X97260D01*
G02X97472Y494607I1J-211D01*
G01Y493607D01*
G02X97260Y493396I-212J1D01*
G01X96460D01*
G02X96248Y493607I-1J211D01*
G01Y494607D01*
G02X96460Y494818I212J-1D01*
G37*
G36*
G01X93612Y453200D02*
Y448799D01*
G02X88788Y448800I-2412J1D01*
G01Y453200D01*
G02X93612I2412J0D01*
G37*
G36*
G01X93940Y438600D02*
Y443001D01*
G02X98762Y443000I2411J-1D01*
G01Y438600D01*
G02X93940I-2411J0D01*
G37*
G36*
G01X97154Y431443D02*
Y430043D01*
G02X96743Y429632I-411J0D01*
G01X95343D01*
G02X94932Y430043I0J411D01*
G01Y431443D01*
G02X95343Y431854I411J0D01*
G01X96743D01*
G02X97154Y431443I0J-411D01*
G37*
G36*
G01X94934Y426030D02*
Y427430D01*
G02X95346Y427842I412J0D01*
G01X96746D01*
G02X97158Y427430I0J-412D01*
G01Y426030D01*
G02X96746Y425618I-412J0D01*
G01X95346D01*
G02X94934Y426030I0J412D01*
G37*
G36*
G01X83500Y342188D02*
X80299D01*
G02X80300Y346212I1J2012D01*
G01X83500D01*
G02Y342188I0J-2012D01*
G37*
G36*
G01X77421Y320458D02*
X74220D01*
G02X74221Y324482I1J2012D01*
G01X77421D01*
G02Y320458I0J-2012D01*
G37*
G36*
G01X76325Y286220D02*
X73124D01*
G02X73125Y290242I1J2011D01*
G01X76325D01*
G02Y286220I0J-2011D01*
G37*
G36*
G01X74200Y218540D02*
X77401D01*
G02X77400Y214516I-1J-2012D01*
G01X74200D01*
G02Y218540I0J2012D01*
G37*
G36*
G01X92000Y208840D02*
X88799D01*
G02X88800Y212862I1J2011D01*
G01X92000D01*
G02Y208840I0J-2011D01*
G37*
G36*
G01X65400Y286244D02*
X62199D01*
G02X62200Y290268I1J2012D01*
G01X65400D01*
G02Y286244I0J-2012D01*
G37*
G36*
G01X65712Y263925D02*
Y260724D01*
G02X61688Y260725I-2012J1D01*
G01Y263925D01*
G02X65712I2012J0D01*
G37*
G36*
G01X57812Y269493D02*
Y266292D01*
G02X53788Y266293I-2012J1D01*
G01Y269493D01*
G02X57812I2012J0D01*
G37*
G36*
G01X56600Y209916D02*
X53399D01*
G02X53400Y213940I1J2012D01*
G01X56600D01*
G02Y209916I0J-2012D01*
G37*
G36*
G01X38050Y218740D02*
X41251D01*
G02X41250Y214716I-1J-2012D01*
G01X38050D01*
G02Y218740I0J2012D01*
G37*
G36*
G01X93279Y570660D02*
X91750Y572189D01*
Y588911D01*
X92789Y589950D01*
X104011D01*
X105150Y588811D01*
Y573089D01*
X101611Y569550D01*
X95952D01*
X95922Y569541D01*
G02X94582I-670J2097D01*
G01X94552Y569550D01*
X94389D01*
X94274Y569665D01*
X94246Y569679D01*
G02X93279Y570660I1006J1959D01*
G37*
G36*
G01X111400Y560298D02*
X106600D01*
G02X106134Y560615I0J501D01*
G02X106090Y560819I458J205D01*
G01Y564820D01*
X106098D01*
Y566200D01*
G02X106600Y566702I502J0D01*
G01X111400D01*
G02X111902Y566200I0J-502D01*
G01Y562219D01*
G02Y562202I-502J-9D01*
G01Y560800D01*
G02X111400Y560298I-502J0D01*
G37*
G36*
G01X108458Y425792D02*
X103258D01*
G02X102846Y426204I0J412D01*
G01Y431195D01*
X102852Y431258D01*
G02X103262Y431632I410J-38D01*
G01X108462D01*
G02X108874Y431220I0J-412D01*
G01Y429620D01*
G02X108871Y429573I-412J3D01*
G01X108870Y429562D01*
Y426204D01*
G02X108458Y425792I-412J0D01*
G37*
G36*
G01X651512Y353708D02*
X656391D01*
G02X656719Y353544I0J-411D01*
G02X656802Y353300I-319J-245D01*
G01Y347900D01*
G02X656797Y347842I-402J5D01*
G02X656471Y347505I-380J41D01*
G02X656400Y347498I-75J395D01*
G01X651600D01*
G02X651500Y347511I1J402D01*
G02X651202Y347829I86J379D01*
G01Y347842D01*
X651201Y347854D01*
G02X651198Y347900I399J49D01*
G01Y353300D01*
G02X651204Y353367I402J-2D01*
G02X651512Y353708I382J-35D01*
G37*
G36*
G01X637318Y348858D02*
Y344756D01*
X633386D01*
Y344754D01*
X632618D01*
Y348854D01*
X633382D01*
Y348858D01*
X637318D01*
G37*
G36*
G01X521407Y335892D02*
X521446Y335907D01*
X521689Y336150D01*
X536811D01*
X537950Y335011D01*
Y318189D01*
X535911Y316150D01*
X521289D01*
X519850Y317589D01*
Y334311D01*
X520143Y334604D01*
X520158Y334643D01*
G02X521407Y335892I2051J-802D01*
G37*
G36*
G01X1162216Y129500D02*
X1157116D01*
G02X1156720Y129694I0J501D01*
G02X1156608Y130010I390J316D01*
G01Y135210D01*
G02X1157110Y135712I502J0D01*
G01X1162210D01*
G02X1162672Y135405I0J-501D01*
G02X1162716Y135200I-456J-205D01*
G01Y130000D01*
G02X1162216Y129500I-500J0D01*
G37*
G36*
G01X520320Y128995D02*
G02X520240Y128988I-84J495D01*
G01X515140D01*
G02X514638Y129490I0J502D01*
G01Y134690D01*
G02X515140Y135192I502J0D01*
G01X520240D01*
G02X520320Y135185I-4J-502D01*
G02X520750Y134690I-70J-495D01*
G01Y129490D01*
G02X520320Y128995I-500J0D01*
G37*
G36*
G01X529259Y129412D02*
G02X528760Y128940I-499J28D01*
G01X523660D01*
G02X523161Y129412I0J500D01*
G02X523158Y129460I499J55D01*
G01Y134660D01*
G02X523660Y135162I502J0D01*
G01X528760D01*
G02X529262Y134660I0J-502D01*
G01Y129460D01*
G02X529259Y129412I-502J7D01*
G37*
G54D54*
X1027722Y-9125D03*
X1054494D03*
G54D51*
X526215Y184000D03*
X565585D03*
G54D47*
X92990Y252362D03*
X116790D03*
X1301120Y173278D03*
Y183908D03*
G54D45*
X16200Y120100D03*
X27200Y821800D03*
X1384200Y122800D03*
X1373200Y823500D03*
G54D49*
X336417Y21260D03*
G54D46*
X42587Y151614D03*
X80579D03*
G54D48*
X293110Y55906D03*
G54D53*
X789850Y236220D03*
Y283464D03*
X1333661Y55905D03*
X1376968Y21259D03*
Y90551D03*
G54D50*
X336417D03*
G54D44*
X75800Y229289D03*
G54D52*
X642793Y352655D03*
G54D43*
X90459Y223184D03*
X64600Y342700D03*
%LPC*%
G75*
G36*
G01X34689Y266050D02*
X23811D01*
X23250Y266611D01*
Y292389D01*
X23911Y293050D01*
X35289D01*
X39550Y288789D01*
Y270911D01*
X34689Y266050D01*
G37*
G36*
G01X46695Y355244D02*
G03X47050Y354841I1818J1243D01*
G01Y329105D01*
X47037Y329071D01*
G03Y327529I2063J-771D01*
G01X47050Y327495D01*
Y327211D01*
X45189Y325350D01*
X24811D01*
X23650Y326511D01*
Y359089D01*
X24711Y360150D01*
X28389D01*
X30489Y358050D01*
X43889D01*
X46695Y355244D01*
G37*
G36*
G01X59689Y702250D02*
X32311D01*
X28750Y705811D01*
Y714189D01*
X30811Y716250D01*
X36311D01*
X40811Y720750D01*
X48311D01*
X49750Y722189D01*
Y726811D01*
X47250Y729311D01*
Y736311D01*
X43811Y739750D01*
X39811D01*
X34311Y745250D01*
X24311D01*
X22250Y747311D01*
Y769689D01*
X35811Y783250D01*
X89189D01*
X96250Y776189D01*
Y739311D01*
X92189Y735250D01*
X76311D01*
X72811Y738750D01*
X61689D01*
X60250Y737311D01*
Y729811D01*
X59689Y729250D01*
X58189D01*
X56750Y727811D01*
Y721689D01*
X63250Y715189D01*
Y705811D01*
X59689Y702250D01*
G37*
G36*
G01X103650Y588189D02*
Y573762D01*
G03X102398Y572484I811J-2047D01*
G01X102383Y572444D01*
X100989Y571050D01*
X95011D01*
X93250Y572811D01*
Y588289D01*
X93411Y588450D01*
X103206D01*
G03X103584Y588255I1194J1850D01*
G01X103650Y588189D01*
G37*
G36*
G01X521911Y317650D02*
X521350Y318211D01*
Y333689D01*
X522311Y334650D01*
X536189D01*
X536450Y334389D01*
Y318811D01*
X535289Y317650D01*
X533280D01*
X533247Y317662D01*
G03X531751I-748J-2071D01*
G01X531718Y317650D01*
X521911D01*
G37*
G36*
G01X596011Y354250D02*
X595250Y355011D01*
Y368889D01*
X595311Y368950D01*
X610289D01*
X610650Y368589D01*
Y354911D01*
X609989Y354250D01*
X597590D01*
G03X597410I-90J-2200D01*
G01X596011D01*
G37*
%LPD*%
G75*
G54D19*
X54378Y237402D03*
G54D40*
X1075197Y92126D03*
Y112126D03*
G54D29*
X213900Y274372D03*
X1348785Y179358D03*
X1323195D03*
G54D14*
X27300Y229000D03*
X26600Y249217D03*
Y253582D03*
X24000Y308700D03*
X24639Y321239D03*
X25350Y389000D03*
X17500Y412374D03*
X20713Y410087D03*
X21300Y429500D03*
X20713Y418326D03*
X23720Y472640D03*
X29300Y539850D03*
X24800Y540900D03*
X26100Y671200D03*
X24000Y659000D03*
X29500Y676500D03*
X25200Y712650D03*
X17500Y706300D03*
X21300Y728400D03*
X21108Y732713D03*
X21250Y742650D03*
X41250Y216728D03*
X53400Y211928D03*
X38050Y216728D03*
X56600Y211928D03*
X60872Y274328D03*
X63700Y260725D03*
X55800Y266293D03*
X63700Y263925D03*
X55800Y269493D03*
X44900Y261750D03*
X35300Y303100D03*
X47912Y294940D03*
X39000Y299500D03*
X53100Y279500D03*
X47800Y309400D03*
X31662Y303262D03*
X58700Y308600D03*
X61800Y306900D03*
X38800Y302900D03*
X62200Y288256D03*
X58383Y294947D03*
X47355Y303376D03*
X47991Y299958D03*
X49934Y280811D03*
X38500Y321400D03*
X58100Y334600D03*
X62400Y334500D03*
X31700Y314700D03*
X52050Y316100D03*
X51050Y321650D03*
X62400Y342700D03*
X38518Y376916D03*
X34153D03*
X39866Y371366D03*
X52521Y350357D03*
X54200Y347400D03*
X63500Y353960D03*
X62838Y392392D03*
X39300Y389557D03*
X35709Y426942D03*
X43500Y418802D03*
X47734Y465792D03*
X45531Y474400D03*
X64820Y455887D03*
X64680Y452389D03*
X64500Y459400D03*
X36750Y462900D03*
X53200Y462500D03*
X49812Y479921D03*
X33900Y469300D03*
X46500Y460300D03*
X46087Y455819D03*
X50140Y494559D03*
X60987Y489223D03*
X63519Y505320D03*
X62298Y484200D03*
X35700Y488500D03*
X60150Y506450D03*
X50140Y490750D03*
X60900Y495122D03*
X61870Y515670D03*
X60300Y533900D03*
X61128Y519646D03*
X61800Y537000D03*
X55950Y564500D03*
Y572500D03*
X63000Y558930D03*
X62611Y608289D03*
X62400Y624500D03*
X53000Y645000D03*
X63300Y634800D03*
X43600Y665700D03*
X54200Y666800D03*
X60700Y682100D03*
X47800Y666400D03*
X35766Y673178D03*
X34500Y666500D03*
X39900Y678100D03*
X33600Y675800D03*
X43100Y670900D03*
X36624Y669155D03*
X45800Y685100D03*
X42100Y684000D03*
X63300Y697200D03*
X59100Y705600D03*
X42130Y694440D03*
X38000Y684000D03*
X88259Y223184D03*
X92659D03*
X78000Y229289D03*
X73600D03*
X77400Y216528D03*
X88800Y210851D03*
X74200Y216528D03*
X92000Y210851D03*
X97480Y266420D03*
X77527Y255800D03*
X94530Y264671D03*
X75800Y274100D03*
X68100Y255000D03*
X89400Y279300D03*
X96798Y301484D03*
Y297915D03*
X95700Y293900D03*
X73125Y288231D03*
X76325D03*
X65400Y288256D03*
X84600Y303000D03*
X66800Y342700D03*
X83500Y344200D03*
X80300D03*
X77421Y322470D03*
X74221D03*
X79455Y357174D03*
X76055Y357145D03*
X82500Y362890D03*
X79267Y410185D03*
X80940Y395989D03*
X86904Y385798D03*
X72708Y382055D03*
X68365Y381464D03*
X84700Y396000D03*
X96351Y443000D03*
Y438600D03*
X85042Y439144D03*
X91200Y448800D03*
Y453200D03*
X89500Y466600D03*
X85748Y475813D03*
X73232Y476912D03*
X97100Y466500D03*
X98400Y454400D03*
X76100Y483400D03*
X77700Y502500D03*
X88573Y503935D03*
X70910Y502219D03*
X67700Y499120D03*
X77700Y522500D03*
X88204Y543283D03*
X89200Y518700D03*
Y528500D03*
X65600Y543200D03*
X75600Y518600D03*
X67700Y518500D03*
X67162Y515142D03*
X77300Y531238D03*
X77700Y538500D03*
X74301Y538390D03*
X65800Y538900D03*
X74300Y533600D03*
X73900Y527050D03*
X77372Y526885D03*
X73700Y542600D03*
X70000Y542500D03*
X74000Y557000D03*
X77500Y554500D03*
X87337Y569268D03*
X84226Y577924D03*
X87200Y565785D03*
X77400Y550400D03*
X65381Y548719D03*
X87608Y557685D03*
X69100Y549200D03*
X73700Y549300D03*
X92000Y591200D03*
X69500Y586000D03*
X66000Y604800D03*
X88000Y613600D03*
X81000Y589000D03*
X78300Y637750D03*
X94950Y677850D03*
X74500Y713400D03*
X91450Y707650D03*
X65350Y690356D03*
X95400Y731600D03*
Y728200D03*
X68900Y730000D03*
X68465Y736229D03*
X85800Y727500D03*
Y731000D03*
X93100Y813200D03*
X93300Y818900D03*
X108631Y168836D03*
X111967Y199632D03*
X119800Y234531D03*
X103100Y211600D03*
X109600Y276850D03*
X112732Y272786D03*
X107340Y266140D03*
X101463Y268811D03*
X102499Y281183D03*
X108500Y284000D03*
X107213Y301192D03*
X120700Y282400D03*
X100500Y285300D03*
X113915Y307600D03*
X117484D03*
X101630Y312236D03*
X106717Y335600D03*
X117700Y323400D03*
X111900Y344200D03*
X113000Y336000D03*
X107558Y321012D03*
X122000Y343300D03*
X100277Y336077D03*
X102000Y364700D03*
X122645Y367966D03*
X117300Y361700D03*
X115951Y384138D03*
X111950Y392050D03*
X104204Y383661D03*
X129500Y412400D03*
X124290Y401910D03*
X125718Y383302D03*
X125600Y386700D03*
X107358Y409942D03*
X126122Y432323D03*
X116235Y444665D03*
X103179Y423267D03*
X103176Y434180D03*
X110406Y417067D03*
X113518Y420179D03*
X131304Y418855D03*
X131004Y422710D03*
X130633Y444763D03*
X120200Y436400D03*
X120000Y451285D03*
X107900Y448900D03*
X101200Y470400D03*
X129520Y448660D03*
X127820Y452280D03*
X123696Y454452D03*
X114400Y550000D03*
X102870Y565740D03*
Y561340D03*
X105851Y611436D03*
X102000Y602500D03*
X101750Y595600D03*
X128220Y620392D03*
X125581Y641436D03*
X109051Y645936D03*
X124150Y707050D03*
X106900Y738600D03*
Y721300D03*
X115000Y717600D03*
X107000Y717800D03*
X111300Y756000D03*
X109900Y828800D03*
X105400Y828700D03*
X103200Y825400D03*
X115500Y825500D03*
X107600D03*
X120000Y843500D03*
X126500Y878200D03*
Y871000D03*
X129000Y875000D03*
X117500Y878200D03*
X122000D03*
X124500Y875000D03*
X120000Y865000D03*
Y875000D03*
Y853500D03*
X162500Y173500D03*
X155026Y212580D03*
X155662Y266438D03*
X159662Y266600D03*
X162910Y244290D03*
X166087Y304350D03*
X134800Y329600D03*
X144595Y312861D03*
X137862Y361723D03*
X161311Y371428D03*
X141216Y361163D03*
X145027D03*
X156573Y371799D03*
X146105Y403610D03*
X155657Y384291D03*
X137000Y436700D03*
X145901Y441262D03*
X153100Y439000D03*
X136500Y417400D03*
X152978Y435602D03*
X137344Y446737D03*
X137000Y451300D03*
X163440Y453020D03*
X143547Y477976D03*
X137000Y454700D03*
X159239Y449079D03*
X159082Y452509D03*
X153019Y622720D03*
X159716Y620392D03*
X166015D03*
X136651Y653036D03*
X162100Y677800D03*
X164400Y668300D03*
X160500Y689500D03*
X150000Y701500D03*
X142500Y709000D03*
X137000Y715500D03*
X164500Y693500D03*
X144400Y731600D03*
Y728200D03*
X150450Y744150D03*
X146450Y736150D03*
X135700Y745200D03*
X163800Y771000D03*
X160400D03*
X160700Y753400D03*
X139250Y791250D03*
X143250Y799250D03*
X153500Y808500D03*
X163800Y820000D03*
X160400D03*
X191800Y189600D03*
X196018Y204200D03*
X183400Y221600D03*
X171100Y247500D03*
X167600Y247600D03*
X193303Y264310D03*
X167700Y296882D03*
Y292517D03*
X170062Y304556D03*
X174943Y321015D03*
X167687Y329434D03*
X192407Y320262D03*
X180571Y327023D03*
X176674Y344934D03*
X189365Y329905D03*
X179381Y369903D03*
X196529Y352284D03*
X185970Y358962D03*
X195940Y348814D03*
X182969Y352641D03*
X192150Y406429D03*
X197000Y404000D03*
X171434Y398093D03*
X177550Y407850D03*
X166321Y388316D03*
X197850Y437450D03*
X185000Y419900D03*
X197531Y451187D03*
X189381Y451394D03*
X193718D03*
X196239Y462262D03*
X175912Y450747D03*
X166534Y450821D03*
X186675Y453505D03*
X177500Y454300D03*
X199900Y544500D03*
X196782Y563564D03*
X197334Y567232D03*
X189500Y567700D03*
X185500Y577300D03*
X184189Y564504D03*
X185500Y567700D03*
X193001Y574708D03*
X181000Y585000D03*
Y581500D03*
Y595200D03*
X168769Y622720D03*
X171300Y678300D03*
X175200Y678500D03*
X199900Y692000D03*
X171000Y715900D03*
X167600D03*
X178750Y712250D03*
X189000Y684500D03*
X185000D03*
X167000Y686500D03*
X199900Y747500D03*
Y741000D03*
X184700Y729400D03*
X182750Y720250D03*
X193000Y729500D03*
X171000Y764900D03*
X167600D03*
X182750Y775750D03*
X178000Y753400D03*
X178750Y767750D03*
X199900Y796500D03*
X177500Y784500D03*
X170800Y808500D03*
X193000Y785000D03*
X197420Y821701D03*
X194120Y830301D03*
X190920D03*
X176900Y867600D03*
X173500D03*
X197218Y871676D03*
X228163Y68589D03*
X222354Y103006D03*
X228163Y78589D03*
X227606Y98642D03*
X223641Y99302D03*
X228163Y93589D03*
Y88589D03*
X228007Y123787D03*
X233500Y137000D03*
X220300Y129300D03*
X222356Y133438D03*
X228708Y127115D03*
X215136Y142786D03*
X218299Y123319D03*
X224576Y116678D03*
X221418Y109634D03*
X210478Y151203D03*
X233537Y160630D03*
X210484Y179525D03*
X206297Y188492D03*
X209866D03*
X214794Y212100D03*
X206200Y247500D03*
X209200Y252800D03*
X230400Y283400D03*
X222200Y300500D03*
X205840Y325381D03*
X210177D03*
X221460Y335475D03*
Y339875D03*
X228100Y364600D03*
X219018Y378000D03*
X223383D03*
X217000Y360000D03*
X219580Y356970D03*
X214776Y352807D03*
X212536Y349805D03*
X205750Y408250D03*
X205915Y422424D03*
X217190Y428485D03*
X212200Y428800D03*
X212000Y438713D03*
X217500Y441992D03*
X205200Y442900D03*
X220897Y441833D03*
X220800Y446000D03*
X200100Y415100D03*
X201868Y451187D03*
X227700Y476537D03*
Y472200D03*
X216404Y469751D03*
X216282Y463288D03*
X230572Y455128D03*
X228900Y446800D03*
X219300Y508700D03*
X228298Y488100D03*
X228347Y484700D03*
X219700Y489800D03*
X202700Y495400D03*
X206700Y498000D03*
X200917Y490578D03*
X203550Y484522D03*
X233290Y493277D03*
X206700Y494000D03*
X203500Y499200D03*
X207026Y483956D03*
X219800Y493700D03*
X218906Y483186D03*
X226300Y505700D03*
X226530Y502307D03*
X216873Y516458D03*
X203300Y538500D03*
X206700Y544500D03*
Y538500D03*
X225000Y541300D03*
X229200Y514800D03*
X216300Y546350D03*
X203300Y544500D03*
Y548500D03*
X219700Y550500D03*
X218780Y560082D03*
X206700Y548500D03*
X202300Y559763D03*
X222300Y577300D03*
X216563Y555908D03*
X229800Y558500D03*
X206700Y554500D03*
X203304Y554684D03*
X205700Y559763D03*
X222500Y573220D03*
X216241Y563095D03*
X227500Y603500D03*
X201000Y674000D03*
X206952Y655370D03*
X203300Y692000D03*
X219000Y694000D03*
X231500Y699000D03*
X217000Y705500D03*
X203300Y747500D03*
Y741000D03*
X210300Y729500D03*
X217000Y761000D03*
X228550Y772700D03*
X231750D03*
X203300Y796500D03*
X210300Y785000D03*
X200620Y821701D03*
X231915Y830301D03*
X219317D03*
X206718D03*
X228715D03*
X216117D03*
X203518D03*
X225615Y875176D03*
X213017D03*
X200418Y871676D03*
X222415Y875176D03*
X209817D03*
X257759Y68589D03*
X264817Y105350D03*
X257731Y78589D03*
X258100Y93589D03*
X257912Y101408D03*
X258029Y97353D03*
X260562Y85988D03*
X254000Y131500D03*
X246500Y139000D03*
X243000D03*
X258068Y110180D03*
X259331Y118580D03*
X264443Y109587D03*
X257422Y121792D03*
X243618Y143381D03*
X243500Y147500D03*
X244300Y226700D03*
X266500Y239400D03*
X245400Y296500D03*
X248160Y343140D03*
X267300Y362200D03*
X244000Y377617D03*
Y381982D03*
X258500Y391200D03*
X239100Y399200D03*
X251700Y421600D03*
Y425200D03*
X238400Y416200D03*
X235750Y419500D03*
X262900Y438700D03*
X246375Y440725D03*
X265100Y443300D03*
X264100Y425400D03*
X249342Y439064D03*
X251800Y470100D03*
X248500Y465000D03*
X263700Y474600D03*
X257493Y456679D03*
X253302D03*
X257400Y477300D03*
X235850Y455050D03*
X246300Y478600D03*
Y485400D03*
X246407Y488799D03*
X256300Y494500D03*
X244100Y499900D03*
X246800Y496800D03*
X257400Y481637D03*
X256300Y486000D03*
Y490000D03*
X242800Y495486D03*
X246500Y493400D03*
X240450Y499400D03*
X236737Y493170D03*
X243200Y508000D03*
X250200Y506600D03*
X264522Y511690D03*
X260407Y502674D03*
X257207D03*
X246300Y482000D03*
X239139Y525077D03*
X239321Y521081D03*
X264500Y521309D03*
X261100Y521250D03*
X250100Y537100D03*
X236100Y517100D03*
X263300Y526300D03*
X234777Y550569D03*
X255738Y574238D03*
X253500Y590500D03*
X257413D03*
X236000Y656000D03*
X256600Y652200D03*
X241000Y712500D03*
X262628Y744470D03*
X266980Y723854D03*
X241000Y721500D03*
X258100Y726100D03*
X241000Y725500D03*
Y718000D03*
X263181Y772181D03*
X266561Y830301D03*
X253962D03*
X263361D03*
X250762D03*
X260261Y875176D03*
X238213D03*
X257061D03*
X235013D03*
X290000Y141100D03*
X274250Y133750D03*
X292000Y130000D03*
X285500D03*
X284440Y139580D03*
X285250Y133750D03*
X294500Y152500D03*
X286000Y143800D03*
X286100Y153900D03*
X280000D03*
X290500Y152500D03*
X275000Y147500D03*
X277800Y208500D03*
X271231Y237031D03*
X283622Y226340D03*
X279257D03*
X277300Y304800D03*
X297090Y311350D03*
X282700Y300100D03*
X299600Y297662D03*
X287200Y326802D03*
X287800Y311600D03*
X267979Y342500D03*
X295400Y325390D03*
X283700Y322100D03*
X288270Y365240D03*
X297729Y351029D03*
X294009Y363063D03*
X293800Y436100D03*
X301170Y462780D03*
X301162Y459290D03*
X273783Y476100D03*
X283400Y477900D03*
X275900Y467300D03*
X285800Y460810D03*
X290838Y501600D03*
X286169Y502000D03*
X285776Y489300D03*
X272860Y489147D03*
X282400Y487300D03*
X295876Y520800D03*
X296200Y566900D03*
X290000Y578165D03*
X279994Y554794D03*
X283600Y551400D03*
X291000Y561450D03*
X280200Y551400D03*
X289835Y583165D03*
Y588165D03*
X269000Y589000D03*
X269335Y593165D03*
X297750Y592750D03*
X281800Y638900D03*
X288400Y626100D03*
Y634200D03*
X292500Y630200D03*
X271500Y639500D03*
X298406Y706000D03*
X290338Y715800D03*
X275609Y726886D03*
X270556Y716702D03*
X269500Y736150D03*
X286500Y740500D03*
X287278Y729031D03*
X286406Y716531D03*
X296132Y726171D03*
X290720Y726333D03*
X285333Y726241D03*
X282406Y716598D03*
X298620Y728596D03*
X283500Y765631D03*
X268193Y755633D03*
X293692Y765571D03*
X287115Y765584D03*
X281500Y752000D03*
X299184Y765691D03*
X279159Y830301D03*
X275959D03*
X285500Y866200D03*
X272859Y875176D03*
X282300Y866200D03*
X269659Y875176D03*
X306900Y251000D03*
X302500Y251600D03*
X311882Y310550D03*
X306800Y290500D03*
X307425Y309838D03*
X303517Y309777D03*
X312900Y290450D03*
X321300Y301500D03*
X334200Y299600D03*
X313200Y299900D03*
X331800Y309100D03*
X310485Y314670D03*
X328800Y315900D03*
X326041Y325000D03*
X310839Y344339D03*
X315300Y344500D03*
X315900Y320900D03*
X313100Y371038D03*
Y374438D03*
X301320Y362500D03*
X301929Y351100D03*
X313500Y437400D03*
Y441000D03*
X313300Y429603D03*
X313294Y434006D03*
X302140Y444160D03*
X306521Y463576D03*
X304293Y466146D03*
X329014Y472022D03*
X322268Y466591D03*
X322305Y469991D03*
X321900Y459800D03*
X322036Y463198D03*
X327512Y509612D03*
X303800Y505100D03*
X304400Y511400D03*
X327589Y504300D03*
X333102Y485902D03*
X330000Y501900D03*
X305500Y483550D03*
X320500Y531000D03*
X321000Y527000D03*
X306900Y529100D03*
X311500Y548000D03*
X314900D03*
X309000Y679000D03*
X305500Y676400D03*
X334800Y712000D03*
X302406Y706031D03*
X306406D03*
X317300Y739300D03*
X302000Y740800D03*
X320000Y718200D03*
X323600Y717800D03*
X301310Y726403D03*
X326000Y729000D03*
X315132Y727197D03*
X307278Y726198D03*
X311200Y765500D03*
X311406Y775198D03*
X302700Y765400D03*
X315406Y765598D03*
Y775200D03*
X307406Y775198D03*
X329553Y830301D03*
X316954D03*
X326353D03*
X313754D03*
X323253Y875176D03*
X310955Y865676D03*
X332651Y875176D03*
X320053D03*
X307755Y865676D03*
X362528Y123931D03*
X358917Y124122D03*
X355069D03*
X352600Y128200D03*
Y132537D03*
X337000Y162000D03*
X354800Y171400D03*
X358300D03*
X354800Y166900D03*
X358300D03*
X354800Y162400D03*
X358300D03*
X362300D03*
Y166900D03*
Y171400D03*
X354800Y181900D03*
X358300D03*
X354800Y176900D03*
X358300D03*
X362300D03*
Y181900D03*
X345820Y256570D03*
X349970Y256720D03*
X341652Y305034D03*
Y301534D03*
X362500Y341700D03*
X362825Y336000D03*
X359132Y326647D03*
X351515Y327915D03*
X356953Y353653D03*
X359403Y351203D03*
X352003Y358603D03*
X354505Y356102D03*
X360820Y359299D03*
X363270Y356940D03*
X355872Y363965D03*
X358362Y361649D03*
X335570Y491460D03*
X367000Y704000D03*
X360000D03*
X344200Y696300D03*
X354300Y696000D03*
Y704500D03*
X363500Y704000D03*
X364354Y731801D03*
X362091Y729538D03*
X367675Y723000D03*
X367348Y830301D03*
X354750D03*
X342151D03*
X364148D03*
X351550D03*
X338951D03*
X361048Y875176D03*
X348450D03*
X335851D03*
X357848D03*
X345250D03*
X401300Y156715D03*
Y153215D03*
X400400Y189100D03*
X383600Y203200D03*
X376600Y261350D03*
X381700Y265800D03*
X368900Y315700D03*
X370700Y353900D03*
X370500Y705500D03*
X370875Y723000D03*
X401994Y830301D03*
X389396D03*
X398794D03*
X386196D03*
X395694Y875176D03*
X383096D03*
X392494D03*
X379896D03*
X403600Y142542D03*
X433000Y169700D03*
X435161Y166892D03*
X403600Y146042D03*
X422876Y199830D03*
Y204195D03*
X421757Y177999D03*
X411400Y183900D03*
X433400Y176800D03*
X410900Y217100D03*
X404040Y318900D03*
Y323300D03*
X427191Y830301D03*
X414593D03*
X423991D03*
X411393D03*
X420891Y875176D03*
X408292D03*
X417691D03*
X405092D03*
X466000Y62300D03*
X457700D03*
X465127Y57727D03*
X454926Y118791D03*
X455800Y110200D03*
X438561Y166892D03*
X456500Y169783D03*
Y165418D03*
X464086Y287614D03*
Y340500D03*
X455450Y376050D03*
X469700Y393300D03*
X459450Y384050D03*
X469000Y784000D03*
X461300Y813100D03*
X457900D03*
X474400Y62300D03*
X483250Y59480D03*
X496782Y134315D03*
X474990Y122660D03*
X480910Y164099D03*
X480800Y160700D03*
X498900Y171800D03*
X498000Y194200D03*
X477037Y333841D03*
X473637Y333876D03*
X500198Y324041D03*
X480532Y321332D03*
X480000Y355800D03*
X476600D03*
X493700Y369300D03*
X487000Y393300D03*
X480368Y405606D03*
X476531D03*
X482925Y777422D03*
X489522Y780127D03*
X478000Y777500D03*
X483850Y773800D03*
X500778Y781031D03*
X499906Y768531D03*
X497910Y778824D03*
X495906Y768598D03*
X480100Y784575D03*
X497000Y817500D03*
X483000Y788150D03*
X499000Y793000D03*
X485300Y811750D03*
X500415Y817532D03*
X494582Y804000D03*
X477206Y820648D03*
X500700Y828100D03*
X500807Y831499D03*
X491906Y827403D03*
X487906D03*
X509369Y141559D03*
X530800Y123900D03*
X507861Y134154D03*
X519300Y138871D03*
X530177Y140708D03*
X516100Y138871D03*
X526977Y140708D03*
X529176Y151713D03*
X532560Y152046D03*
X534000Y167400D03*
X535960Y151999D03*
X507300Y175500D03*
X503975Y172372D03*
X518686Y163800D03*
Y168200D03*
X517599Y229658D03*
X531232Y229927D03*
X510462Y261315D03*
X525881Y287776D03*
X509143Y284391D03*
X529881Y287376D03*
X529126Y342336D03*
X532978Y371023D03*
X534500Y395100D03*
X528850Y394750D03*
X515900Y768300D03*
X531500Y774500D03*
X531600Y770200D03*
X515278Y779198D03*
X519748Y768297D03*
X507729Y778198D03*
X504278Y779198D03*
X507906Y768531D03*
X528179Y782555D03*
X524795Y778529D03*
X511484Y778515D03*
X515650Y764500D03*
X503906Y768598D03*
X519906Y764900D03*
X532000Y792500D03*
X515000D03*
X524700Y817500D03*
X507044Y817569D03*
X516943Y817401D03*
X528906Y817598D03*
X512716Y817550D03*
X508579Y827421D03*
X527500Y836200D03*
X512679Y827500D03*
X562603Y140881D03*
X544800Y137769D03*
X541600D03*
X549100Y126900D03*
X566531Y143123D03*
X570754Y147365D03*
X546800Y163450D03*
X564483Y167935D03*
X558121Y167249D03*
X548700Y152200D03*
X545500D03*
X547173Y167987D03*
X561567Y205767D03*
X569500Y240225D03*
X546494Y216010D03*
X539798Y228856D03*
X539934Y232660D03*
X540035Y236294D03*
X541637Y263240D03*
X545974D03*
X541681Y297976D03*
X539481Y286676D03*
X544993Y281352D03*
X539400Y376444D03*
X561300Y369500D03*
X552720Y364180D03*
X539400Y380781D03*
X559973Y387638D03*
X561912Y390762D03*
X567150Y415750D03*
X560900Y413700D03*
X544000Y761000D03*
X540500Y781000D03*
X547395Y761198D03*
X540500Y761000D03*
X561050Y830301D03*
X548451D03*
X570448D03*
X557850D03*
X545251D03*
X567348Y875176D03*
X554750D03*
X542151D03*
X564148D03*
X551550D03*
X538951D03*
X577650Y137780D03*
X587850Y137800D03*
X604450Y137780D03*
X574450D03*
X584650Y137800D03*
X601250Y137780D03*
X597350Y149950D03*
X594150D03*
X596253Y210000D03*
X603000Y190710D03*
X579811Y179500D03*
X582400Y209500D03*
X597813Y220858D03*
X587438Y230850D03*
X576100Y234500D03*
X592563Y228308D03*
X588963Y227408D03*
X587400Y238200D03*
X600800Y337400D03*
X597600Y339100D03*
X604400Y421200D03*
X579900Y427400D03*
X598845Y830301D03*
X586246D03*
X573648D03*
X595645D03*
X583046D03*
X592545Y875176D03*
X579947D03*
X601944D03*
X589345D03*
X576747D03*
X614721Y138287D03*
X608089Y131519D03*
X627826Y137880D03*
X638150D03*
X624626D03*
X634950D03*
X617000Y144500D03*
X636950Y149650D03*
X635482Y207733D03*
X607700Y211800D03*
X608800Y221400D03*
X635863Y216308D03*
X635190Y219641D03*
X631063Y242108D03*
X616970Y235017D03*
X629663Y221708D03*
X616718Y238408D03*
X627363Y224358D03*
X637300Y234500D03*
X628563Y249108D03*
X624101Y330010D03*
X627500Y329900D03*
X622629Y344635D03*
X616640Y342230D03*
X620000Y341500D03*
X618600Y357100D03*
X609000Y390350D03*
X615500Y420100D03*
X619100Y418000D03*
X636640Y830301D03*
X624042D03*
X611443D03*
X633440D03*
X620842D03*
X608243D03*
X630340Y875176D03*
X617742D03*
X605144D03*
X627140D03*
X614542D03*
X654500Y143000D03*
X647000D03*
X640150Y149650D03*
X640400Y218200D03*
X649400Y234500D03*
X642463Y241608D03*
X638963D03*
X660700Y212000D03*
X643000Y343000D03*
X643750Y321500D03*
X640550D03*
X643000Y369500D03*
X648792Y358431D03*
X660244Y352200D03*
Y349000D03*
X645800Y780500D03*
Y776900D03*
Y783900D03*
X671285Y830301D03*
X658687D03*
X668085D03*
X655487D03*
X664986Y875176D03*
X652388D03*
X661786D03*
X649188D03*
X687900Y208100D03*
X697494Y186256D03*
Y181919D03*
X693300Y181200D03*
X674500Y212000D03*
X680100Y378718D03*
X683600D03*
X696482Y830301D03*
X683884D03*
X693282D03*
X680684D03*
X702400Y868800D03*
X690183Y875176D03*
X677585D03*
X699200Y868800D03*
X686983Y875176D03*
X674385D03*
X728395Y-7315D03*
X713461Y-3006D03*
X729132Y3575D03*
X724018Y5719D03*
X729000Y24800D03*
X725314Y24751D03*
X721890Y24887D03*
X719008Y21999D03*
X707051Y12174D03*
X738384Y8232D03*
X722955Y33095D03*
X726155D03*
X723200Y42300D03*
X726609Y49251D03*
Y46051D03*
X732900Y44900D03*
X730021Y42235D03*
X732500Y98421D03*
X720800Y102150D03*
Y93150D03*
Y78150D03*
X732500Y101621D03*
X720800Y105350D03*
Y96350D03*
Y81350D03*
Y114150D03*
Y117350D03*
X713000Y310000D03*
X712495Y816195D03*
X727978Y830301D03*
X737377D03*
X724778D03*
X714900Y818600D03*
X734277Y875176D03*
X731077D03*
X746329Y-7789D03*
X771715Y6840D03*
X741600Y41000D03*
X742290Y68550D03*
X750130Y63340D03*
X748300Y53800D03*
X772000Y64200D03*
X755700Y79100D03*
X749800Y91400D03*
X753700Y102900D03*
X759600Y79200D03*
X743490Y111940D03*
X765000Y112800D03*
X768777Y171450D03*
X761242Y169242D03*
X765579D03*
X766950Y189252D03*
X763562Y189539D03*
X770385Y189165D03*
X749337Y212192D03*
X746037Y213992D03*
X746237Y210392D03*
X765774Y830301D03*
X753175D03*
X740577D03*
X762574D03*
X749975D03*
X772073Y875176D03*
X759474D03*
X746876D03*
X768873D03*
X756274D03*
X743676D03*
X790150Y-1400D03*
X788408Y-4321D03*
X798061Y-6439D03*
X806152Y51692D03*
X791300Y74200D03*
X775381Y66115D03*
X778800Y66388D03*
X782551Y67144D03*
X786333Y66963D03*
X791200Y125300D03*
X806665Y174050D03*
X803265D03*
X792760Y176043D03*
X799000Y196000D03*
X802200D03*
X792000Y195778D03*
X787600Y195804D03*
X773984Y189118D03*
X792760Y180443D03*
X778807Y183890D03*
Y179490D03*
X803569Y830301D03*
X790970D03*
X778372D03*
X800369D03*
X787770D03*
X775172D03*
X797270Y875176D03*
X784671D03*
X806668D03*
X794070D03*
X781471D03*
X807514Y2199D03*
X813900Y12900D03*
X838252Y20800D03*
X834500D03*
X830500D03*
X828283Y24734D03*
X824462Y25770D03*
X821877Y21090D03*
X823996Y44276D03*
X820004Y44234D03*
X828700Y48800D03*
X808114Y67634D03*
X816043Y94981D03*
Y99318D03*
X823551Y80551D03*
X819000Y97100D03*
X809000Y76000D03*
X810000Y109400D03*
X840500Y735500D03*
X837000D03*
X839990Y789230D03*
X816167Y830301D03*
X838164D03*
X812967D03*
X835065Y875176D03*
X809868D03*
X831865D03*
X861000Y350D03*
X857453Y303D03*
X863300Y23575D03*
X851100Y9100D03*
X849051Y20908D03*
X845052Y20800D03*
X841652D03*
X858500Y28000D03*
X858100Y21400D03*
X858500Y36000D03*
X847000Y9100D03*
X870600Y18915D03*
X854252Y20800D03*
X851870Y52160D03*
X848623Y70757D03*
X852019Y70589D03*
X855421Y70551D03*
X858821Y70614D03*
X859000Y43500D03*
X871550Y56450D03*
X858800Y52200D03*
X868800Y49200D03*
Y85300D03*
X871696Y87082D03*
X868200Y116000D03*
X846702Y117371D03*
X854400Y117500D03*
X861300Y117800D03*
X864800Y707700D03*
X868200D03*
X852895Y748648D03*
X869406Y745531D03*
X848000Y735500D03*
X865406Y745598D03*
X873367Y745335D03*
X844000Y735500D03*
X854049Y757573D03*
X857406Y755198D03*
X861406D03*
X858126Y763600D03*
X841500Y771000D03*
X874000Y772000D03*
X869562Y758457D03*
X844500Y758000D03*
X867410Y755824D03*
X866878Y794531D03*
X853500Y798000D03*
X846706Y797648D03*
X870278Y794531D03*
X874570Y811820D03*
X861406Y804403D03*
X857406D03*
X853962Y830301D03*
X841364D03*
X850762D03*
X847663Y875176D03*
X844463D03*
X883800Y-500D03*
X881700Y2300D03*
X899769Y4355D03*
X896500Y9500D03*
X877500Y23600D03*
X900250Y38150D03*
X888474Y9173D03*
X900200Y9600D03*
X883800Y41400D03*
X900501Y48705D03*
X883700Y50700D03*
X905488Y54479D03*
X878394Y85780D03*
X875001Y86003D03*
X901899Y85942D03*
X892900Y85300D03*
X885042Y85292D03*
X888600Y85700D03*
X897600Y85500D03*
X895800Y738400D03*
X893400Y745100D03*
X884700Y721100D03*
X896500Y734000D03*
X877000Y745000D03*
X892100Y721100D03*
X881200Y721300D03*
X888400Y721400D03*
X889900Y769600D03*
X884778Y756198D03*
X876036Y755481D03*
X894465Y755501D03*
X891056Y755641D03*
X882227Y758835D03*
X894200Y794500D03*
X877930Y796880D03*
X876470Y808710D03*
X906396Y810300D03*
X886288Y794372D03*
X898700Y794200D03*
Y816000D03*
X882290Y796770D03*
X881720Y807390D03*
X906450Y806900D03*
X906092Y813687D03*
X894406Y818000D03*
X888100Y823338D03*
X890200Y819200D03*
X911800Y37000D03*
X938000Y30300D03*
X919400Y33300D03*
X915486Y41030D03*
X918952Y40680D03*
X939064Y58104D03*
X934881Y57322D03*
X909797Y55037D03*
X910000Y85300D03*
X937642Y85562D03*
X926093Y85239D03*
X929213Y86593D03*
X934438Y86700D03*
X919050Y85500D03*
X913979Y86580D03*
X929800Y105900D03*
X974100Y19600D03*
X970064Y18764D03*
X963700Y21700D03*
X959877Y26978D03*
X967180Y66705D03*
X949102Y74964D03*
X947900Y67900D03*
X959300Y68600D03*
Y72000D03*
X964105Y62308D03*
X959855Y61107D03*
X956687Y85482D03*
X942800Y85700D03*
X948200Y85900D03*
X953301Y85793D03*
X949893Y106378D03*
X949828Y109778D03*
X960500Y607000D03*
X953500D03*
X956900D03*
X1008353Y-1940D03*
X985579Y26494D03*
X985403Y22993D03*
X994650Y39880D03*
X990628Y49698D03*
X997007Y49560D03*
X1008508Y47704D03*
X1022711Y-4975D03*
X1012177Y-2940D03*
X1019859Y-7642D03*
X1033017Y14743D03*
X1033554Y30216D03*
X1040121Y26870D03*
X1039822Y35743D03*
X1017908Y41556D03*
X1018900Y14198D03*
X1010975Y29017D03*
X1029553Y13981D03*
X1030139Y30209D03*
X1024432Y43718D03*
X1011300Y53000D03*
X1024318Y51554D03*
X1014700Y53700D03*
X1040241Y61043D03*
X1033517Y48934D03*
X1036854Y47110D03*
X1019900Y108500D03*
X1015948D03*
X1034500D03*
X1027483Y108431D03*
X1024000Y108500D03*
X1037900D03*
X1041300D03*
X1030883Y108438D03*
X1028500Y257500D03*
X1041314Y830301D03*
X1038214Y875176D03*
X1035014D03*
X1062044Y-4173D03*
X1065620Y-4335D03*
X1072800Y-800D03*
X1045850Y6228D03*
X1069200Y-4200D03*
X1060800Y10100D03*
X1044050Y28815D03*
X1062088Y40597D03*
X1072804Y19894D03*
X1064900Y10400D03*
X1065700Y32888D03*
Y36088D03*
X1061200Y20888D03*
Y24088D03*
X1056200Y10100D03*
X1065657Y28946D03*
X1047500Y41500D03*
X1051000D03*
X1076970Y30411D03*
X1052600Y14400D03*
X1049772Y57259D03*
X1049470Y53749D03*
X1050875Y61090D03*
X1057000Y54500D03*
X1071135Y60375D03*
X1057000Y57700D03*
X1071135Y57175D03*
X1057000Y107700D03*
X1057259Y77276D03*
X1048100Y108500D03*
X1044700D03*
X1061000Y111000D03*
X1053000Y109500D03*
X1069711Y830301D03*
X1057112D03*
X1044514D03*
X1066511D03*
X1053912D03*
X1076010Y875176D03*
X1050813D03*
X1072810D03*
X1047613D03*
X1084000Y500D03*
X1083315Y36654D03*
X1082808Y30601D03*
X1092094Y30362D03*
X1080672Y9500D03*
X1084800Y9400D03*
X1083379Y40889D03*
X1083500Y25500D03*
X1082974Y14467D03*
X1105441Y54768D03*
X1100992Y52374D03*
X1078694Y43478D03*
X1077432Y64225D03*
X1103300Y73900D03*
X1103349Y70700D03*
X1088005Y46541D03*
X1088287Y55917D03*
X1096496Y51226D03*
X1107506Y830301D03*
X1094907D03*
X1082309D03*
X1104306D03*
X1091707D03*
X1079109D03*
X1101207Y875176D03*
X1088608D03*
X1110605D03*
X1098007D03*
X1085408D03*
X1112700Y80700D03*
X1114842Y83078D03*
X1122001Y133324D03*
X1141900Y137851D03*
X1122001Y130124D03*
X1138700Y137851D03*
X1143000Y242000D03*
X1132703Y830301D03*
X1120104D03*
X1142101D03*
X1129503D03*
X1116904D03*
X1139002Y875176D03*
X1126403D03*
X1113805D03*
X1135802D03*
X1123203D03*
X1161307Y138505D03*
X1158107D03*
X1170400Y144100D03*
X1147000Y242000D03*
X1151000D03*
X1157899Y830301D03*
X1145301D03*
X1176747D03*
X1154699D03*
X1164199Y875176D03*
X1151600D03*
X1160999D03*
X1148400D03*
X1182061Y142478D03*
X1190835Y137899D03*
X1199400Y142851D03*
X1178861Y142478D03*
X1187635Y137899D03*
X1196200Y142851D03*
X1206991Y156730D03*
X1203791D03*
X1201000Y417900D03*
X1196600Y416200D03*
X1192545Y830301D03*
X1179947D03*
X1189345D03*
X1199000Y867200D03*
X1186246Y875176D03*
X1195800Y867300D03*
X1183046Y875176D03*
X1214795Y142443D03*
X1234209Y142463D03*
X1242900Y137851D03*
X1225348Y137960D03*
X1231009Y142463D03*
X1239700Y137851D03*
X1222148Y137960D03*
X1242621Y153690D03*
X1226000Y261300D03*
X1236640Y830301D03*
X1224042D03*
X1233440D03*
X1220842D03*
X1242939Y875176D03*
X1230340D03*
X1239739D03*
X1227140D03*
X1277265Y137673D03*
X1274065D03*
X1273499Y151498D03*
X1273520Y148070D03*
X1261944Y145770D03*
X1258744D03*
X1251801Y144871D03*
X1275500Y264500D03*
X1255000Y317300D03*
X1270500Y335500D03*
X1272500Y350000D03*
X1275060Y345690D03*
X1277620Y349500D03*
X1264820Y349320D03*
X1249250Y390250D03*
X1269500Y397000D03*
X1273500Y400500D03*
X1258000Y421500D03*
X1274435Y830301D03*
X1261837D03*
X1249239D03*
X1271235D03*
X1258637D03*
X1246039D03*
X1268136Y875176D03*
X1255537D03*
X1277534D03*
X1264936D03*
X1252337D03*
X1303983Y22083D03*
X1304000Y44000D03*
Y67500D03*
Y90500D03*
X1286543Y141581D03*
X1296017Y137478D03*
X1283343Y141581D03*
X1292817Y137478D03*
X1290000Y271000D03*
X1308500Y262500D03*
X1311200Y256500D03*
X1293500Y271000D03*
X1312200Y275200D03*
X1303700Y289500D03*
X1288900Y304000D03*
X1283300Y302900D03*
X1309900Y292400D03*
X1310500Y285500D03*
X1281900Y346580D03*
X1282740Y350010D03*
X1293280Y345770D03*
X1289960Y349900D03*
X1299000Y347500D03*
X1311500Y391000D03*
X1310068Y394084D03*
X1297625Y382375D03*
X1296500Y386500D03*
X1290125Y382875D03*
X1289500Y386500D03*
X1282740Y383000D03*
X1282000Y386500D03*
X1301000Y618500D03*
X1300000Y637000D03*
X1297617Y677117D03*
X1286800Y671100D03*
X1297500Y664000D03*
X1310207D03*
X1297400Y651300D03*
X1290550D03*
X1302000Y695500D03*
X1302128Y685500D03*
X1307000Y686500D03*
X1304500Y698000D03*
X1301728Y714600D03*
X1312132Y684293D03*
X1310500Y723000D03*
X1291428Y726117D03*
X1306128Y732872D03*
X1302128D03*
X1312231Y830301D03*
X1287033D03*
X1309031D03*
X1283833D03*
X1305931Y875176D03*
X1293333D03*
X1280734D03*
X1302731D03*
X1290133D03*
X1339471Y139268D03*
X1316590Y147210D03*
X1317400Y143620D03*
X1340130Y145980D03*
X1331243Y182198D03*
X1322000Y276500D03*
X1322500Y266800D03*
X1333500Y290500D03*
X1317026Y304858D03*
X1314000Y286500D03*
X1313607Y664000D03*
X1327200Y661800D03*
X1331000Y662000D03*
X1326128Y674000D03*
X1340000D03*
X1317007Y664000D03*
X1334128Y674000D03*
X1337500Y698000D03*
X1322439Y697767D03*
X1315000Y686500D03*
X1329500Y684667D03*
X1321928Y683798D03*
X1318500Y684667D03*
X1339934Y683832D03*
X1336795Y685141D03*
X1326758Y686678D03*
X1314628Y733000D03*
X1315000Y723000D03*
X1333500D03*
X1334128Y732667D03*
X1325600Y722987D03*
X1342000Y732500D03*
X1337500Y723000D03*
X1340500Y742500D03*
X1338128Y732872D03*
X1330128Y732667D03*
X1337427Y830301D03*
X1324829D03*
X1346825D03*
X1334227D03*
X1321629D03*
X1343726Y875176D03*
X1331128D03*
X1318529D03*
X1340526D03*
X1327928D03*
X1315329D03*
X1359128Y167226D03*
X1355321Y172119D03*
X1354971Y167446D03*
X1365804Y185197D03*
X1355066Y275228D03*
X1348500Y276500D03*
X1361500Y273500D03*
X1352000Y276700D03*
X1352500Y267000D03*
X1369300Y259300D03*
X1355000Y286300D03*
X1364000Y280500D03*
X1351500Y675000D03*
X1350025Y830301D03*
X1381696Y173459D03*
X1387196Y174160D03*
X1382138Y184129D03*
X1385467Y180543D03*
G54D24*
X131700Y275700D03*
X125100Y282500D03*
X131700Y280000D03*
X300500Y715613D03*
G54D21*
X92990Y252362D03*
X116790D03*
X1301120Y173278D03*
Y183908D03*
G54D32*
X473231Y235560D03*
Y274930D03*
G54D36*
X533010Y69803D03*
X535962Y64292D03*
X524151Y69803D03*
X527104Y64292D03*
X535962Y49331D03*
X527104D03*
X533010Y54843D03*
X524151D03*
X533010Y99725D03*
X535962Y94213D03*
X524151Y99725D03*
X527104Y94213D03*
X533010Y84764D03*
X535962Y79252D03*
X524151Y84764D03*
X527104Y79252D03*
X567458Y54843D03*
X570411Y49331D03*
Y64292D03*
X567458Y69803D03*
X541868D03*
X544821Y64292D03*
Y49331D03*
X541868Y54843D03*
X570411Y79252D03*
Y94213D03*
X567458Y84764D03*
Y99725D03*
X541868D03*
X544821Y94213D03*
X541868Y84764D03*
X544821Y79252D03*
X576317Y54843D03*
X585175D03*
X579269Y49331D03*
X588128D03*
X576317Y69803D03*
X585175D03*
X579269Y64292D03*
X588128D03*
X579269Y79252D03*
X588128D03*
X585175Y84764D03*
X576317D03*
Y99725D03*
X585175D03*
X579269Y94213D03*
X588128D03*
X619624Y54843D03*
X628482D03*
X622577Y49331D03*
X631435D03*
X619624Y69803D03*
X628482D03*
X622577Y64292D03*
X631435D03*
X610766Y54843D03*
X613718Y49331D03*
Y64292D03*
X610766Y69803D03*
X622577Y79252D03*
X631435D03*
X628482Y84764D03*
X619624D03*
Y99725D03*
X628482D03*
X622577Y94213D03*
X631435D03*
X613718Y79252D03*
Y94213D03*
X610766Y84764D03*
Y99725D03*
X662931Y54843D03*
X671789D03*
X665884Y49331D03*
X662931Y69803D03*
X671789D03*
X665884Y64292D03*
X654073Y54843D03*
X657025Y49331D03*
Y64292D03*
X654073Y69803D03*
X665884Y79252D03*
X671789Y84764D03*
X662931D03*
Y99725D03*
X671789D03*
X665884Y94213D03*
X657025Y79252D03*
Y94213D03*
X654073Y84764D03*
Y99725D03*
X674742Y49331D03*
Y64292D03*
Y79252D03*
Y94213D03*
X1135372Y69803D03*
X1144230D03*
X1138324Y64292D03*
X1126513Y69803D03*
X1129466Y64292D03*
X1138324Y49331D03*
X1129466D03*
X1144230Y54843D03*
X1135372D03*
X1126513D03*
X1135372Y99725D03*
X1144230D03*
X1138324Y94213D03*
X1126513Y99725D03*
X1129466Y94213D03*
X1135372Y84764D03*
X1144230D03*
X1138324Y79252D03*
X1126513Y84764D03*
X1129466Y79252D03*
X1178679Y54843D03*
Y69803D03*
X1169820Y54843D03*
X1172773Y49331D03*
Y64292D03*
X1169820Y69803D03*
X1147183Y64292D03*
Y49331D03*
X1178679Y84764D03*
Y99725D03*
X1172773Y79252D03*
Y94213D03*
X1169820Y84764D03*
Y99725D03*
X1147183Y94213D03*
Y79252D03*
X1187537Y54843D03*
X1181631Y49331D03*
X1190490D03*
X1187537Y69803D03*
X1181631Y64292D03*
X1190490D03*
X1181631Y79252D03*
X1190490D03*
X1187537Y84764D03*
Y99725D03*
X1181631Y94213D03*
X1190490D03*
X1221986Y54843D03*
X1230844D03*
X1224939Y49331D03*
X1233797D03*
X1221986Y69803D03*
X1230844D03*
X1224939Y64292D03*
X1233797D03*
X1213128Y54843D03*
X1216080Y49331D03*
Y64292D03*
X1213128Y69803D03*
X1224939Y79252D03*
X1233797D03*
X1230844Y84764D03*
X1221986D03*
Y99725D03*
X1230844D03*
X1224939Y94213D03*
X1233797D03*
X1216080Y79252D03*
Y94213D03*
X1213128Y84764D03*
Y99725D03*
X1265293Y54843D03*
X1274151D03*
X1268246Y49331D03*
X1277104D03*
X1265293Y69803D03*
X1274151D03*
X1268246Y64292D03*
X1277104D03*
X1256435Y54843D03*
X1259387Y49331D03*
Y64292D03*
X1256435Y69803D03*
X1268246Y79252D03*
X1277104D03*
X1274151Y84764D03*
X1265293D03*
Y99725D03*
X1274151D03*
X1268246Y94213D03*
X1277104D03*
X1259387Y79252D03*
Y94213D03*
X1256435Y84764D03*
Y99725D03*
G54D26*
X108200Y775800D03*
X112700Y775300D03*
Y770800D03*
X108200D03*
X103700D03*
Y775800D03*
Y766300D03*
X108200D03*
X112700D03*
X223000Y184000D03*
Y188500D03*
X225000Y192500D03*
X229200D03*
X243000Y176500D03*
X243500Y166500D03*
Y162000D03*
Y157000D03*
X243000Y181000D03*
Y186000D03*
X239900Y600100D03*
X240000Y608600D03*
Y604400D03*
X536081Y304376D03*
X536809Y298789D03*
X553563Y306108D03*
Y310608D03*
X557904Y327115D03*
X562123Y319158D03*
X553455Y314807D03*
X553463Y319108D03*
X557863D03*
X585515Y276459D03*
X583009Y264117D03*
X585351Y269292D03*
X587984Y246148D03*
X587980Y251975D03*
X589164Y264150D03*
X582738Y273300D03*
X587063Y257608D03*
X582976Y246148D03*
X583286Y251974D03*
X582682Y257614D03*
X589400Y308626D03*
X585737Y289608D03*
Y283108D03*
X582683Y279618D03*
X582411Y286589D03*
X582363Y293408D03*
X580563Y308608D03*
X583391Y298870D03*
X583282Y303091D03*
X670063Y274708D03*
X669633Y259148D03*
X704537Y221492D03*
X689623Y269648D03*
X694963Y269608D03*
X689723Y274748D03*
X694223D03*
X679723D03*
X684223D03*
X690233Y255748D03*
X695000Y255800D03*
X690133Y260348D03*
X694633D03*
X680133Y259148D03*
X684633D03*
X674563Y274708D03*
X674133Y259148D03*
X695963Y302308D03*
Y297808D03*
Y293308D03*
X690663Y287608D03*
Y292108D03*
X712337Y207792D03*
X712137Y213292D03*
Y219392D03*
X738800Y272000D03*
Y265500D03*
Y258000D03*
Y251500D03*
X706800Y272500D03*
Y265500D03*
Y258000D03*
Y252000D03*
X715300Y272000D03*
Y265500D03*
Y258000D03*
Y251500D03*
X724300Y272000D03*
Y265500D03*
Y258000D03*
Y251500D03*
X732300Y272000D03*
Y265500D03*
Y258000D03*
Y251500D03*
X921300Y74700D03*
X918100Y71900D03*
X929464Y49420D03*
X925022Y42909D03*
X929713Y44849D03*
X985880Y41686D03*
Y46086D03*
Y50586D03*
X1177600Y241200D03*
X1173400D03*
X1166400Y234300D03*
X1170600D03*
X1175700D03*
X1177200Y248200D03*
X1173000D03*
X1177300Y254400D03*
X1173100D03*
X1176300Y261500D03*
X1171200D03*
X1167000D03*
X1203100Y241100D03*
X1198900D03*
X1207900D03*
X1182400Y241200D03*
X1197900Y234300D03*
X1207400D03*
X1203200D03*
X1179900D03*
X1188900D03*
X1184700D03*
X1193700D03*
X1182000Y248200D03*
X1202600Y254100D03*
X1198400D03*
X1207400D03*
X1202500Y247500D03*
X1198300D03*
X1207300D03*
X1182100Y254400D03*
X1203800Y261500D03*
X1208000D03*
X1194300D03*
X1198500D03*
X1185300D03*
X1189500D03*
X1180500D03*
X1212900Y234300D03*
X1233900Y240700D03*
X1239900D03*
X1244900D03*
X1228900D03*
X1228500Y235000D03*
X1234000D03*
X1240000D03*
X1245000D03*
X1214000Y261500D03*
X1233800Y246600D03*
X1239800D03*
X1244800D03*
X1228800D03*
X1229000Y252000D03*
X1245000D03*
X1240000D03*
X1234000D03*
X1255900Y240700D03*
X1249900D03*
X1262500Y235000D03*
X1250000D03*
X1256000D03*
X1255800Y246600D03*
X1249800D03*
X1262000Y252000D03*
X1256000D03*
X1250000D03*
X1360844Y210366D03*
X1355944Y210313D03*
X1351525Y207104D03*
X1351545Y202879D03*
Y198575D03*
X1378115Y189144D03*
X1374000Y192500D03*
Y188300D03*
Y196700D03*
X1378500Y198000D03*
X1378115Y193344D03*
X1351777Y227823D03*
X1360644Y223881D03*
X1350987Y236754D03*
X1351668Y232125D03*
X1355644Y223881D03*
X1351899Y219598D03*
X1351954Y215268D03*
X1354989Y239016D03*
X1350950Y241000D03*
X1349639Y211374D03*
X1349298Y223737D03*
X1355050Y247300D03*
X1350950Y246100D03*
X1382500Y193500D03*
Y188000D03*
G54D38*
X943111Y5908D03*
X935236D03*
X927361D03*
X919486D03*
X911616D03*
X943111Y13778D03*
X935236D03*
X927361D03*
X919486D03*
X958856Y5908D03*
X950986D03*
X958856Y13778D03*
X950986D03*
G54D18*
X41603Y177598D03*
X65579D03*
X57587D03*
X49595D03*
X45559Y187598D03*
X37567D03*
X53551D03*
X73571Y177598D03*
X81563D03*
X77607Y187598D03*
X69615D03*
X85599D03*
G54D25*
X122700Y476100D03*
Y478400D03*
X122600Y473800D03*
Y471500D03*
X121673Y491672D03*
X130985Y504300D03*
X124822Y504271D03*
X127973Y504272D03*
X121673Y497973D03*
Y494822D03*
X118500Y504238D03*
X115373Y504271D03*
X127973Y510571D03*
X124823D03*
X121673D03*
X131121Y513721D03*
X121673D03*
X131121Y510570D03*
X127971Y513721D03*
X124821D03*
X127971Y494823D03*
X131122Y491674D03*
X127973Y488524D03*
X131122D03*
Y485374D03*
X121673Y504272D03*
X124823Y501122D03*
X121673D03*
X127973Y497973D03*
X124822Y488523D03*
X127973Y491674D03*
X124823Y497973D03*
Y491674D03*
X127973Y485374D03*
X124823Y494822D03*
X131121Y494823D03*
X127973Y501122D03*
Y529469D03*
X124823Y523170D03*
Y532617D03*
X124822Y545216D03*
X131122Y532618D03*
X124823Y535766D03*
X127973Y538918D03*
X127996Y535781D03*
X121673Y545215D03*
Y523170D03*
X131121Y529467D03*
Y520018D03*
X127971D03*
X131121Y523168D03*
X124822Y520019D03*
X121673Y520020D03*
X115374Y529467D03*
X118524D03*
X121673D03*
X124823D03*
X121673Y532617D03*
X124822Y538917D03*
X121673Y535766D03*
X127973Y523170D03*
X121673Y538916D03*
X126801Y574386D03*
X124900Y559638D03*
X124847Y550110D03*
X124900Y556462D03*
Y565990D03*
Y562814D03*
Y553286D03*
X122547Y561276D03*
Y554924D03*
Y567628D03*
X125072Y610945D03*
X125070Y598347D03*
X131370Y601496D03*
X118773Y601495D03*
X126646Y606400D03*
X115622Y614094D03*
Y601496D03*
X121922Y610945D03*
X128220Y614095D03*
X118773Y604645D03*
X125070Y614095D03*
X118773Y598345D03*
X118805Y614099D03*
X115623Y598345D03*
X118773Y610945D03*
X131369Y614095D03*
X118773Y589748D03*
X128221Y610945D03*
X121922Y588872D03*
X118773Y592048D03*
X125072Y620392D03*
X121921D03*
X140571Y491674D03*
X140570Y488523D03*
X162618Y485374D03*
X150020Y491674D03*
X156319Y485374D03*
X143721Y491674D03*
Y488524D03*
Y485374D03*
X140569Y494823D03*
X134270Y510571D03*
Y504272D03*
X146869Y494823D03*
X153168D03*
X159467D03*
X165768Y488524D03*
X153170Y491674D03*
X150020Y485374D03*
Y482225D03*
X146870Y485374D03*
Y488524D03*
X162618D03*
Y491674D03*
X134272D03*
X165768D03*
X134272Y488524D03*
Y485374D03*
X137421Y491674D03*
Y485374D03*
X140571D03*
X156318Y488523D03*
X156319Y491674D03*
X153169Y485374D03*
Y488524D03*
X159469Y491674D03*
Y488524D03*
Y485374D03*
X150020Y488524D03*
X137421D03*
X165766Y542066D03*
X143721Y532618D03*
X137421Y535768D03*
Y542066D03*
X134270Y538916D03*
X137421Y532618D03*
X134272Y542066D03*
Y535768D03*
X140570Y535767D03*
X137421Y538918D03*
X153188Y538899D03*
X162617Y535766D03*
X146869Y538954D03*
X146858Y535742D03*
X159449Y542048D03*
Y538898D03*
X159456Y532642D03*
X162617Y542066D03*
Y538916D03*
X149981Y538917D03*
X153132Y535767D03*
X149985Y535771D03*
X153194Y542078D03*
X153187Y532636D03*
X140571Y532618D03*
X143718Y538953D03*
X143686Y542070D03*
X146869Y529469D03*
X134270Y523170D03*
X153168Y529469D03*
X140569D03*
X134270Y516869D03*
X159467Y529469D03*
X134272Y532618D03*
X162618D03*
X165766Y538916D03*
X161280Y564000D03*
X147451Y551836D03*
Y549536D03*
X142951Y551036D03*
X161280Y566300D03*
X159537Y548256D03*
X147451Y556436D03*
X142951Y555636D03*
X160700Y551356D03*
X151989Y557138D03*
X161280Y556100D03*
X151989Y554838D03*
X161280Y558400D03*
X137669Y610945D03*
Y601495D03*
X140818D03*
X134521Y595196D03*
X134519Y614095D03*
X150269Y598347D03*
X156566Y614095D03*
X143968Y601495D03*
X140821Y614106D03*
X166016Y601496D03*
X159716Y610945D03*
Y614095D03*
Y595197D03*
X166016Y610944D03*
X162867Y614095D03*
X147115Y598360D03*
X150268Y601496D03*
X147141Y614096D03*
X143968Y588898D03*
X153417Y610945D03*
X159716Y604645D03*
X166015Y598345D03*
X147117Y610945D03*
X162865Y601495D03*
X150268Y610944D03*
X159716Y601495D03*
X140818Y610945D03*
X134520Y610944D03*
X153418Y592048D03*
X159716D03*
X134521Y598345D03*
X143968Y592048D03*
X147117Y601495D03*
X150251Y617226D03*
X134521Y617266D03*
X137671D03*
X140821D03*
X156566Y617244D03*
X159716D03*
X150351Y620436D03*
X181514Y479075D03*
X172065Y513721D03*
X175215D03*
X178365Y510571D03*
X175215D03*
X172065D03*
Y501122D03*
X178365Y507422D03*
X175215D03*
Y491674D03*
Y497973D03*
X172065Y491674D03*
X175215Y485374D03*
X175217Y482225D03*
X175215Y501122D03*
X178365D03*
X184664Y485372D03*
X172065Y494823D03*
X178365Y491674D03*
X181514Y488524D03*
X184664Y488522D03*
X175215Y494823D03*
X172065Y497973D03*
X178365Y494823D03*
X172065Y485374D03*
X172067Y482225D03*
X178365Y497973D03*
X172065Y504272D03*
X175216Y504271D03*
X172065Y507422D03*
X178365Y504272D03*
X168916Y510571D03*
Y504272D03*
X178365Y513721D03*
X172065Y488524D03*
X175216Y488523D03*
X178365Y485374D03*
Y488524D03*
X181514Y485374D03*
X178365Y520020D03*
X181514D03*
X172065Y535768D03*
Y526319D03*
X178365Y529469D03*
X175215D03*
X172065D03*
X175215Y523170D03*
X178365D03*
X175216Y535767D03*
X168916Y523170D03*
Y516870D03*
X184665Y520019D03*
X178365Y526319D03*
X175215D03*
Y532618D03*
X178365Y535768D03*
X172065Y532618D03*
X175215Y538918D03*
X168916Y535766D03*
X172065Y538918D03*
X168916Y542066D03*
Y538916D03*
X178365Y532618D03*
X874410Y139764D03*
Y131890D03*
Y120079D03*
Y124016D03*
Y155512D03*
Y147638D03*
Y206692D03*
Y194881D03*
Y183071D03*
Y230314D03*
Y222440D03*
Y214566D03*
X894095Y131890D03*
X898032Y139764D03*
Y131890D03*
Y135827D03*
X905906Y127953D03*
X901969Y139764D03*
Y135827D03*
Y131890D03*
X886221Y139764D03*
X890158Y135827D03*
X886221Y131890D03*
X890158Y139764D03*
X894095Y135827D03*
X890158Y131890D03*
X878347Y135827D03*
Y116142D03*
X882284Y120079D03*
X886221Y116142D03*
X890158Y120079D03*
X894095Y116142D03*
X898032Y120079D03*
X901969Y116142D03*
X878347Y139764D03*
X882284Y135827D03*
X878347Y131890D03*
Y120079D03*
X882300Y124032D03*
X886221Y120079D03*
X890158Y124016D03*
X894095Y120079D03*
X898032Y124016D03*
X901969Y120079D03*
X905906Y139764D03*
Y135827D03*
Y131890D03*
X894095Y163386D03*
X898032D03*
Y167323D03*
Y171260D03*
Y175197D03*
X901969Y163386D03*
X905906D03*
X898032Y143701D03*
Y147638D03*
Y151575D03*
Y155512D03*
Y159449D03*
X901969Y147638D03*
Y143701D03*
X890158Y159449D03*
X886221Y155512D03*
X890158Y151575D03*
X886221Y147638D03*
X890158Y143701D03*
X894095Y159449D03*
X890158Y155512D03*
X894095Y151575D03*
X890158Y147638D03*
X894095Y143701D03*
X878347Y159449D03*
Y151575D03*
Y143701D03*
X882284Y159449D03*
X878347Y155512D03*
X882284Y151575D03*
X878347Y147638D03*
X882284Y143701D03*
X905906Y155512D03*
Y151575D03*
Y147638D03*
Y143701D03*
X901969Y155512D03*
Y151575D03*
X898032Y194881D03*
Y198818D03*
Y202755D03*
X894095D03*
X898032Y179134D03*
Y183071D03*
Y190944D03*
X905906Y183071D03*
X901969D03*
X886221Y206692D03*
X890158Y198818D03*
X886221Y194881D03*
X890158Y190944D03*
X886221Y183071D03*
X890158Y179134D03*
Y206692D03*
X894095Y198818D03*
X890158Y194881D03*
X894095Y190944D03*
X890158Y183071D03*
X894095Y179134D03*
X878347Y198818D03*
Y190944D03*
Y206692D03*
X882284Y198818D03*
X878347Y194881D03*
X882284Y190944D03*
X878347Y183071D03*
X898032Y238188D03*
X894095D03*
X898032Y234251D03*
Y230314D03*
X905906Y238188D03*
X901969D03*
X898032Y226377D03*
Y222440D03*
Y218503D03*
Y214566D03*
Y210629D03*
X890158Y234251D03*
X886221Y230314D03*
X890158Y226377D03*
X886221Y222440D03*
X890158Y218503D03*
X886221Y214566D03*
X890158Y210629D03*
X905906Y242125D03*
X898032D03*
X890158D03*
X882284D03*
X894095Y234251D03*
X890158Y230314D03*
X894095Y226377D03*
X890158Y222440D03*
X894095Y218503D03*
X890158Y214566D03*
X894095Y210629D03*
X878347Y234251D03*
Y226377D03*
Y218503D03*
Y210629D03*
X882284Y234251D03*
X878347Y230314D03*
X882284Y226377D03*
X878347Y222440D03*
X882284Y218503D03*
X878347Y214566D03*
X882284Y210629D03*
X905906Y246062D03*
X901969Y249999D03*
X898032Y246062D03*
X894095Y249999D03*
X890158Y246062D03*
X886221Y249999D03*
X882284Y246062D03*
X878347Y249999D03*
X901969Y246062D03*
X894095D03*
X886221D03*
X878347D03*
X905906Y257873D03*
X901969Y261810D03*
X898032Y257873D03*
X894095Y261810D03*
X890158Y257873D03*
X886221Y261810D03*
X882284Y257873D03*
X878347Y261810D03*
X905906Y253936D03*
X901969Y257873D03*
X898032Y253936D03*
X894095Y257873D03*
X890158Y253936D03*
X886221Y257873D03*
X882284Y253936D03*
X878347Y257873D03*
X909843Y131890D03*
X941339Y127953D03*
X913780Y131890D03*
Y127953D03*
Y139764D03*
X921654Y127953D03*
X929528D03*
X937402Y139764D03*
Y127953D03*
X921654Y139764D03*
X929528D03*
X925591D03*
X921654Y131890D03*
X941339D03*
Y135827D03*
X933465Y131890D03*
Y135827D03*
X937402Y131890D03*
Y135827D03*
X929528Y131890D03*
Y135827D03*
X925591Y131890D03*
Y135827D03*
X909843Y120079D03*
X913780Y116142D03*
X917717Y120079D03*
X921654Y116142D03*
X925591Y120079D03*
X929528Y116142D03*
X933465Y120079D03*
X937402Y116142D03*
X909843Y124016D03*
X913780Y120079D03*
X917717Y124016D03*
X921654Y120079D03*
X925591Y124016D03*
X929528Y120079D03*
X933465Y124016D03*
X937402Y120079D03*
X913780Y135827D03*
X917717Y139764D03*
Y131890D03*
Y135827D03*
X909843Y139764D03*
X937402Y155512D03*
X941339Y151575D03*
Y155512D03*
X929528Y159449D03*
X913780Y143701D03*
Y159449D03*
X937402Y175197D03*
X941339Y171260D03*
X937402Y167323D03*
X941339Y163386D03*
X929528Y175197D03*
X933465Y171260D03*
X929528Y167323D03*
X933465Y163386D03*
X925591Y171260D03*
X921654Y175197D03*
X925591Y163386D03*
X921654Y167323D03*
X917717Y163386D03*
Y171260D03*
X921654Y159449D03*
X937402D03*
X925591Y151575D03*
X913780Y147638D03*
X917717Y159449D03*
X913780Y155512D03*
Y151575D03*
X933465D03*
Y155512D03*
X921654Y151575D03*
X929528D03*
Y155512D03*
X925591Y143701D03*
Y147638D03*
Y155512D03*
X909843Y159449D03*
Y143701D03*
Y155512D03*
X941339Y143701D03*
Y147638D03*
X933465Y143701D03*
Y147638D03*
X937402Y143701D03*
Y147638D03*
X929528Y143701D03*
Y147638D03*
X917717Y155512D03*
Y151575D03*
Y143701D03*
Y147638D03*
X921654Y155512D03*
X917717Y179134D03*
X913780Y183071D03*
X921654Y194881D03*
X917717Y198818D03*
X937402Y194881D03*
X933465Y198818D03*
X929528Y202755D03*
X925591Y206692D03*
X929528Y194881D03*
X925591Y198818D03*
X921654Y202755D03*
X917717Y206692D03*
X933465D03*
X937402Y202755D03*
X941339Y198818D03*
Y206692D03*
X925591Y190944D03*
X933465Y179134D03*
X929528Y183071D03*
X925591Y179134D03*
X921654Y183071D03*
X941339Y190944D03*
X933465D03*
X937402Y183071D03*
X941339Y179134D03*
X917717Y190944D03*
X921654Y238188D03*
X917717D03*
Y214566D03*
X913780Y238188D03*
X909843D03*
X913780Y214566D03*
X941339Y226377D03*
X937402Y222440D03*
X933465Y226377D03*
X929528Y222440D03*
X925591Y226377D03*
X929528Y230314D03*
X937402D03*
X941339Y234251D03*
X937402Y238188D03*
X933465Y234251D03*
X929528Y238188D03*
X925591Y234251D03*
X921654Y210629D03*
X925591Y214566D03*
X929528Y210629D03*
X941339Y214566D03*
X933465D03*
X937402Y210629D03*
X941339Y242125D03*
X933465D03*
X925591D03*
X917717D03*
X941339Y246062D03*
X937402Y249999D03*
X933465Y246062D03*
X929528Y249999D03*
X925591Y246062D03*
X921654Y249999D03*
X917717Y246062D03*
X913780Y249999D03*
X937402Y246062D03*
X929528D03*
X921654D03*
X913780D03*
X941339Y257873D03*
X937402Y261810D03*
X933465Y257873D03*
X929528Y261810D03*
X925591Y257873D03*
X921654Y261810D03*
X917717Y257873D03*
X913780Y261810D03*
X941339Y253936D03*
X937402Y257873D03*
X933465Y253936D03*
X929528Y257873D03*
X925591Y253936D03*
X921654Y257873D03*
X917717Y253936D03*
X913780Y257873D03*
X953149Y127953D03*
X949212D03*
Y139764D03*
X957086Y127953D03*
X964960D03*
X972834D03*
X957086Y139764D03*
X972834D03*
X953149D03*
Y131890D03*
X957086D03*
X964960D03*
X961023Y139764D03*
Y131890D03*
Y135827D03*
X957086D03*
Y116142D03*
X961023Y120079D03*
X964960Y116142D03*
X968897Y120079D03*
X972834Y116142D03*
X957086Y120079D03*
X961023Y124016D03*
X964960Y120079D03*
X968897Y124016D03*
X972834Y120079D03*
Y135827D03*
Y131890D03*
X964960Y135827D03*
Y139764D03*
X968897Y135827D03*
Y131890D03*
X949212Y155512D03*
X953149Y163386D03*
X949212Y167323D03*
X964960D03*
X968897Y163386D03*
X957086Y175197D03*
X961023Y171260D03*
X953149D03*
X949212Y175197D03*
X961023Y163386D03*
X957086Y167323D03*
X972834D03*
X968897Y171260D03*
X964960Y175197D03*
X972834D03*
X968897Y151575D03*
X964960Y159449D03*
X957086D03*
X953149Y151575D03*
X949212Y159449D03*
X972834D03*
Y151575D03*
X957086Y143701D03*
X961023D03*
X957086Y151575D03*
Y147638D03*
Y155512D03*
X953149Y143701D03*
Y155512D03*
X949212Y143701D03*
Y147638D03*
X964960Y143701D03*
X961023Y155512D03*
Y151575D03*
X964960Y155512D03*
Y151575D03*
X968897Y155512D03*
X964960Y147638D03*
X968897D03*
Y143701D03*
X972834D03*
Y155512D03*
X949212Y194881D03*
X968897Y198818D03*
X964960Y202755D03*
X961023Y206692D03*
X972834Y194881D03*
X953149Y206692D03*
X964960Y194881D03*
X961023Y198818D03*
X957086Y202755D03*
X949212D03*
X953149Y198818D03*
X957086Y194881D03*
X972834Y202755D03*
X968897Y206692D03*
X949212Y183071D03*
X953149Y179134D03*
X961023D03*
X957086Y183071D03*
X953149Y190944D03*
X968897D03*
X972834Y183071D03*
X961023Y190944D03*
X964960Y183071D03*
X968897Y179134D03*
X972834Y238188D03*
X968897Y226377D03*
Y234251D03*
X953149Y226377D03*
X949212Y222440D03*
Y230314D03*
X964960Y222440D03*
X961023Y226377D03*
X957086Y222440D03*
X964960Y230314D03*
X957086D03*
X953149Y234251D03*
X949212Y238188D03*
X964960D03*
X961023Y234251D03*
X957086Y238188D03*
X953149Y214566D03*
X957086Y210629D03*
X949212D03*
X972834D03*
X968897Y214566D03*
X961023D03*
X964960Y210629D03*
X968897Y242125D03*
X961023D03*
X953149D03*
X972834Y249999D03*
X968897Y246062D03*
X964960Y249999D03*
X961023Y246062D03*
X957086Y249999D03*
X953149Y246062D03*
X972834D03*
X964960D03*
X957086D03*
X972834Y261810D03*
X968897Y257873D03*
X964960Y261810D03*
X961023Y257873D03*
X957086Y261810D03*
X953149Y257873D03*
X972834D03*
X968897Y253936D03*
X964960Y257873D03*
X961023Y253936D03*
X957086Y257873D03*
X953149Y253936D03*
X992519Y139764D03*
X996456D03*
Y131890D03*
Y135827D03*
X1000393Y131890D03*
X980708Y127953D03*
Y139764D03*
Y135827D03*
Y131890D03*
X1008267Y139764D03*
X976771Y120079D03*
X980708Y116142D03*
X984645Y120079D03*
X1008267Y131890D03*
X1004330Y135827D03*
Y139764D03*
X976771Y124016D03*
X980708Y120079D03*
X984645Y124016D03*
X1004330Y131890D03*
X1000393Y135827D03*
X992519Y115742D03*
X996456Y120079D03*
X1000393Y116142D03*
X1004330Y120079D03*
X1008267Y116142D03*
X992519Y120079D03*
X996456Y124016D03*
X1000393Y120079D03*
X1004330Y124016D03*
X1008267Y120079D03*
X988582Y139764D03*
Y135827D03*
X984645Y131890D03*
X976771D03*
Y139764D03*
X988582Y131890D03*
X984645Y139764D03*
X976771Y135827D03*
X996456Y163386D03*
X1000393D03*
X996456Y167323D03*
Y171260D03*
Y175197D03*
X992519Y163386D03*
X988582D03*
X980708Y175197D03*
X996456Y143701D03*
Y147638D03*
Y151575D03*
Y155512D03*
Y159449D03*
X976771Y163386D03*
Y171260D03*
X980708Y159449D03*
Y155512D03*
X976771Y151575D03*
X1004330Y143701D03*
X1008267Y147638D03*
X1004330Y151575D03*
X1008267Y155512D03*
X1004330Y159449D03*
X1008267Y167323D03*
X1004330Y171260D03*
X1008267Y175197D03*
X1000393Y143701D03*
X1004330Y147638D03*
X1000393Y151575D03*
X1004330Y155512D03*
X1000393Y159449D03*
X1004330Y167323D03*
X1000393Y171260D03*
X1004330Y175197D03*
X988582Y147638D03*
Y143701D03*
X984645Y155512D03*
Y151575D03*
Y143701D03*
X988582Y151575D03*
X976771Y147638D03*
X980708Y143701D03*
X976771Y155512D03*
X980708Y147638D03*
Y151575D03*
X976771Y159449D03*
Y143701D03*
X996456Y194881D03*
Y198818D03*
Y202755D03*
X1000393D03*
X996456Y179134D03*
Y183071D03*
Y190944D03*
X992519Y183071D03*
X988582D03*
X976771Y179134D03*
X980708Y183071D03*
X976771Y206692D03*
Y198818D03*
Y190944D03*
X1004330Y179134D03*
X1008267Y183071D03*
X1004330Y190944D03*
X1008267Y194881D03*
X1004330Y198818D03*
X1008267Y206692D03*
X1000393Y179134D03*
X1004330Y183071D03*
X1000393Y190944D03*
X1004330Y194881D03*
X1000393Y198818D03*
X1004330Y206692D03*
X992519Y238188D03*
X988582D03*
X984645D03*
X980708D03*
X1000393D03*
X996456D03*
Y234251D03*
Y230314D03*
Y226377D03*
Y222440D03*
Y218503D03*
Y214566D03*
Y210629D03*
X976771Y238188D03*
Y214566D03*
X980708D03*
X1004330Y210629D03*
X1008267Y214566D03*
X1004330Y218503D03*
X1008267Y222440D03*
X1004330Y226377D03*
X1008267Y230314D03*
X1004330Y234251D03*
X1000393Y210629D03*
X1004330Y214566D03*
X1000393Y218503D03*
X1004330Y222440D03*
X1000393Y226377D03*
X1004330Y230314D03*
X1000393Y234251D03*
X1004330Y242125D03*
X996456D03*
X988582D03*
X976771D03*
X1008267Y249999D03*
X1004330Y246062D03*
X1000393Y249999D03*
X996456Y246062D03*
X992519Y249999D03*
X988582Y246062D03*
X980708Y249999D03*
X976771Y246062D03*
X1008267D03*
X1000393D03*
X992519D03*
X980708D03*
X1008267Y261810D03*
X1004330Y257873D03*
X1000393Y261810D03*
X996456Y257873D03*
X992519Y261810D03*
X988582Y257873D03*
X980708Y261810D03*
X976771Y257873D03*
X1008267D03*
X1004330Y253936D03*
X1000393Y257873D03*
X996456Y253936D03*
X992519Y257873D03*
X988582Y253936D03*
X980708Y257873D03*
X976771Y253936D03*
X1020078Y139764D03*
X1012204Y120079D03*
X1016141Y116142D03*
X1020078Y120079D03*
Y131890D03*
X1016141Y135827D03*
Y139764D03*
X1012204Y124016D03*
X1016141Y120079D03*
X1023278D03*
X1016141Y131890D03*
X1012204Y135827D03*
X1016141Y143701D03*
X1020078Y147638D03*
X1016141Y151575D03*
X1020078Y155512D03*
X1016141Y159449D03*
X1020078Y167323D03*
X1016141Y171260D03*
X1020078Y175197D03*
X1012204Y143701D03*
X1016141Y147638D03*
X1012204Y151575D03*
X1016141Y155512D03*
X1012204Y159449D03*
X1016141Y167323D03*
X1012204Y171260D03*
X1016141Y175197D03*
Y179134D03*
X1020078Y183071D03*
X1016141Y190944D03*
X1020078Y194881D03*
X1016141Y198818D03*
X1020078Y206692D03*
X1012204Y179134D03*
X1016141Y183071D03*
X1012204Y190944D03*
X1016141Y194881D03*
X1012204Y198818D03*
X1016141Y206692D03*
X1012204Y242125D03*
X1016141Y210629D03*
X1020078Y214566D03*
X1016141Y218503D03*
X1020078Y222440D03*
X1016141Y226377D03*
X1020078Y230314D03*
X1016141Y234251D03*
X1012204Y210629D03*
X1016141Y214566D03*
X1012204Y218503D03*
X1016141Y222440D03*
X1012204Y226377D03*
X1016141Y230314D03*
X1012204Y234251D03*
X1016141Y249999D03*
X1012204Y246062D03*
X1016141D03*
Y261810D03*
X1012204Y257873D03*
X1016141D03*
X1012204Y253936D03*
G54D23*
X134251Y153543D03*
X151968D03*
X144094D03*
X1027722Y-9125D03*
X1054494D03*
G54D31*
X476614Y167493D03*
Y162493D03*
Y157493D03*
G54D28*
X193900Y274372D03*
X183900D03*
X203900D03*
X302500Y207200D03*
X292500D03*
X326200D03*
X336200D03*
X312500D03*
X346200D03*
X465485Y200680D03*
Y190680D03*
Y180680D03*
X488462Y180761D03*
Y190761D03*
Y200761D03*
X526215Y184000D03*
X511742Y215594D03*
X521742D03*
X531742D03*
X565585Y184000D03*
X772300Y16200D03*
X762300D03*
X752300D03*
X785300Y16100D03*
X795300D03*
X805300D03*
X1348785Y161642D03*
X1323195D03*
G54D12*
X31977Y126614D03*
Y116614D03*
X91189Y126614D03*
Y116614D03*
Y136614D03*
G54D34*
X487404Y255245D03*
G54D20*
X58400Y271800D03*
X57500Y263300D03*
X63700Y257300D03*
X63800Y267100D03*
X44426Y267408D03*
X59173Y288186D03*
X71094Y285981D03*
X77964Y285670D03*
X68429Y288212D03*
X75450Y694150D03*
X130900Y714300D03*
Y710800D03*
X107950Y687650D03*
X111400Y741800D03*
Y718300D03*
X118060Y743460D03*
X136400Y738300D03*
Y721800D03*
X623498Y140671D03*
X886221Y171260D03*
G54D11*
X18577Y107902D03*
X5500Y119571D03*
Y139571D03*
Y159571D03*
X22000Y167200D03*
X5500Y179571D03*
Y199571D03*
X26500Y199500D03*
X21900Y199700D03*
X21800Y188100D03*
X5500Y219571D03*
Y239571D03*
X23100Y224500D03*
X28400Y262800D03*
X18000Y271600D03*
X5500Y259571D03*
X18000Y289400D03*
X28200Y296100D03*
X5500Y279571D03*
Y299571D03*
X26300Y317600D03*
X21400Y327900D03*
Y341000D03*
X5500Y339571D03*
Y319571D03*
X21400Y354000D03*
X22900Y365300D03*
X5500Y359571D03*
Y399571D03*
Y379571D03*
X31324Y410800D03*
X5500Y419571D03*
Y439571D03*
Y479571D03*
Y459571D03*
Y499571D03*
Y519571D03*
Y539571D03*
Y579571D03*
Y559571D03*
Y599571D03*
Y639571D03*
Y619571D03*
Y679571D03*
Y659571D03*
Y699571D03*
X27125Y695275D03*
X18250Y749250D03*
X5500Y719571D03*
Y739571D03*
X27000Y754400D03*
X5500Y779571D03*
Y759571D03*
Y799571D03*
X10020Y835051D03*
X30020D03*
X5500Y819571D03*
X31400Y209190D03*
X46760Y209157D03*
X63250Y205050D03*
X42800Y200100D03*
X44400Y216600D03*
X34900Y216800D03*
X59800Y211800D03*
X50200Y212000D03*
X31500Y224400D03*
X44029Y272572D03*
X35150Y273250D03*
X42900Y284500D03*
X58730Y299508D03*
X35150Y284350D03*
X49100Y328300D03*
X39600Y317600D03*
X58990Y342700D03*
X34800Y321200D03*
X54600Y328600D03*
X31500Y366900D03*
X48512Y356488D03*
X49300Y346700D03*
X43262Y357062D03*
X44866Y378634D03*
X55907Y350673D03*
X60610Y381665D03*
X47132Y444399D03*
X48000Y426000D03*
Y422500D03*
Y429500D03*
X57800Y420700D03*
X31500Y447000D03*
X64200Y534500D03*
X62000Y713000D03*
X53500Y690200D03*
X60650Y694050D03*
X56590Y720410D03*
X47800Y772900D03*
X35000Y769900D03*
X39000D03*
X42800Y770000D03*
X52500Y779600D03*
X64900Y780500D03*
X50020Y835051D03*
X96584Y195100D03*
X78050Y196300D03*
X82676Y208785D03*
X67600Y209500D03*
X92859Y226659D03*
X87978Y226596D03*
X78508Y232693D03*
X72934Y232675D03*
X95200Y210800D03*
X85600D03*
X80600Y216700D03*
X71000Y216600D03*
X88276Y232700D03*
X94600Y277100D03*
X93672Y270153D03*
X71870Y257120D03*
X75400Y309700D03*
X78121Y325870D03*
X73721D03*
X70210Y342700D03*
X77290Y344212D03*
X86511Y344200D03*
X66400Y334500D03*
X75256Y370303D03*
X70591Y359309D03*
X71794Y377639D03*
X92580Y410761D03*
X79600Y399200D03*
X95223Y385704D03*
X92752Y434193D03*
X91370Y445394D03*
X70700Y443244D03*
X77859Y429879D03*
X72533Y416996D03*
X79164Y426221D03*
X91311Y456609D03*
X89400Y470400D03*
X77681Y499033D03*
X77413Y506468D03*
X90500Y580100D03*
X81000Y579000D03*
X95252Y571638D03*
X70800Y559895D03*
X77400Y559000D03*
X77250Y562750D03*
X77400Y577000D03*
X71400Y578300D03*
X87555Y561085D03*
X87200Y574250D03*
X90500Y587000D03*
X80300Y596100D03*
X69258Y603000D03*
X82000Y592500D03*
X78300Y634250D03*
X94860Y628750D03*
X75800Y681900D03*
X69700Y690300D03*
X89825Y692875D03*
X79250Y716050D03*
X91800Y716100D03*
X66700Y713500D03*
X74300Y769950D03*
X69800Y772700D03*
X86900Y757900D03*
X89400Y762400D03*
X70020Y835051D03*
X90020D03*
X118577Y107902D03*
X104000Y128330D03*
X114364Y122054D03*
X118500Y176500D03*
Y173000D03*
X100900Y173800D03*
X116000Y207000D03*
Y202000D03*
X118500Y188500D03*
X116000Y192000D03*
Y196500D03*
X118500Y185000D03*
Y181000D03*
X104100Y194600D03*
X103700Y200800D03*
X116000Y211500D03*
X113300Y276600D03*
X127330Y248029D03*
X112764Y264218D03*
X109810Y310358D03*
X113000Y280500D03*
X113100Y284100D03*
X109972Y305968D03*
X112217Y296435D03*
X106400Y312200D03*
X99128Y366961D03*
X108200Y378656D03*
X126800Y362500D03*
X108484Y348377D03*
X108453Y385164D03*
X100924Y409968D03*
X105303Y419497D03*
X116173Y422379D03*
X107844Y414785D03*
X99749Y443671D03*
X99818Y437908D03*
X127925Y428093D03*
X115500Y454700D03*
X111500D03*
X103500D03*
X118524Y491672D03*
X124823Y542067D03*
X127973Y532618D03*
Y542067D03*
X104461Y571715D03*
X100140Y559260D03*
X99460Y566200D03*
X126869Y577770D03*
X122547Y564452D03*
Y558100D03*
Y551748D03*
X121601Y574686D03*
X104400Y590300D03*
X131369Y610945D03*
X115622Y604646D03*
X121911Y614076D03*
X102000Y599000D03*
X131369Y588898D03*
X121922Y592048D03*
X118771Y595196D03*
X121922Y617244D03*
X128221D03*
X120351Y633500D03*
X126851Y633449D03*
X116551Y644936D03*
X131369Y617244D03*
X118771D03*
X125070D03*
X131051Y656436D03*
X119051Y653906D03*
X109800Y681900D03*
X132200Y761300D03*
Y756300D03*
X138577Y107902D03*
X158577D03*
X149380Y176010D03*
X163000Y211500D03*
X157200Y241400D03*
X153000Y225000D03*
X134120Y267630D03*
X157300Y259900D03*
X157400Y254000D03*
X157300Y246500D03*
X139286Y311214D03*
X158170Y314302D03*
X162670D03*
X153670D03*
X156170Y318302D03*
X160670D03*
X143000Y342900D03*
X155891Y339730D03*
X140500Y390500D03*
X145500Y385500D03*
X158800Y406255D03*
X143000Y388000D03*
X142608Y403594D03*
X157550Y399100D03*
X139019Y443177D03*
X159540Y445692D03*
X146165Y444876D03*
X149838Y446190D03*
X150431Y420306D03*
X133000Y454700D03*
X146870Y491674D03*
Y482225D03*
X150020Y510571D03*
X153169D03*
X146870D03*
X153169Y513721D03*
X146870D03*
X150020D03*
X146870Y516870D03*
X150020D03*
X153169D03*
X151989Y552538D03*
X147451Y554136D03*
X142951Y553336D03*
X161280Y553800D03*
Y561700D03*
X143968Y614095D03*
X143967Y610945D03*
X137669Y604645D03*
X162865Y595196D03*
Y604645D03*
X156566Y610945D03*
X159716Y598345D03*
X153417Y614095D03*
X150269D03*
X153418Y595197D03*
X162865Y610945D03*
X137661Y614096D03*
X137670Y595197D03*
X147143Y595184D03*
X165851Y630651D03*
X137551Y629849D03*
X149851Y631251D03*
X155851Y631051D03*
X160851Y630651D03*
X150069Y640500D03*
X150280Y636620D03*
X150600Y648300D03*
X150409Y643884D03*
X143969Y617244D03*
X162881Y617266D03*
X153417Y617244D03*
X161200Y723900D03*
X150200Y729400D03*
X153700D03*
X157700Y748900D03*
X154000Y779000D03*
X143000Y784500D03*
X146500D03*
X150500Y804000D03*
X138500Y835000D03*
X137600Y839500D03*
X141100Y824500D03*
X141000Y830700D03*
X145900Y824400D03*
X142500Y862500D03*
Y867500D03*
Y872500D03*
X138500Y869500D03*
Y875200D03*
X141000Y877700D03*
X145500D03*
X149700D03*
X142500Y856500D03*
X159449Y878276D03*
X178577Y107902D03*
X181738Y122711D03*
X171500Y207500D03*
Y202500D03*
X193400Y192900D03*
X167000Y211500D03*
X172450Y211050D03*
X180850Y285650D03*
X176098Y444355D03*
X173471Y454700D03*
X184664Y516869D03*
X172065Y523170D03*
Y520020D03*
X175216Y520019D03*
X197500Y577300D03*
X198600Y599750D03*
Y588750D03*
X181371Y601636D03*
X193500Y700000D03*
X182500Y705500D03*
X186000D03*
X190000Y725000D03*
X177700Y723900D03*
X182860Y742240D03*
X181200Y748900D03*
X190000Y780500D03*
X170500Y779000D03*
X193500Y755500D03*
X182500Y761000D03*
X186000D03*
X175660Y797340D03*
X174000Y804000D03*
X195000Y824090D03*
X188572Y832186D03*
X196474Y832178D03*
X196000Y868700D03*
X176771Y878276D03*
X195669D03*
X168898Y878200D03*
X185500D03*
X227669Y5500D03*
X210028Y12605D03*
Y32605D03*
Y52605D03*
Y72605D03*
X226533Y72591D03*
X228121Y63589D03*
X210028Y92605D03*
X227989Y83589D03*
X228500Y138100D03*
X223750Y141370D03*
X218725Y138175D03*
X224500Y170500D03*
Y174700D03*
Y166300D03*
X213282Y188452D03*
X202892Y188441D03*
X224500Y178900D03*
X205013Y192596D03*
X218102Y334880D03*
X218070Y340244D03*
X219763Y472187D03*
X216600Y496550D03*
X217800Y512500D03*
X221000Y541300D03*
X217500Y519800D03*
Y529250D03*
X216300Y550500D03*
X216278Y567341D03*
X216090Y593937D03*
X210000Y700000D03*
X213500Y725000D03*
X215160Y718340D03*
X227409Y775903D03*
X233000D03*
X213500Y780500D03*
X210000Y755500D03*
X215160Y773840D03*
X203124Y824090D03*
X233650Y827374D03*
X208700Y828000D03*
X201641Y827947D03*
X214380Y827374D03*
X221052D03*
X226978D03*
X201500Y868700D03*
X233464Y878276D03*
X208267D03*
X201969D03*
X220866D03*
X214567D03*
X227166D03*
X247669Y5500D03*
X258159Y73589D03*
X257851Y63589D03*
X257769Y83589D03*
X264500Y142750D03*
X259500Y138500D03*
X254500Y142750D03*
X259500Y143250D03*
Y147750D03*
Y160750D03*
Y156250D03*
X264397Y160977D03*
X264500Y157250D03*
Y153750D03*
Y150250D03*
Y146250D03*
X259500Y152000D03*
X254500Y161250D03*
Y157250D03*
Y153750D03*
Y150250D03*
Y146250D03*
X261500Y173500D03*
X253000Y166500D03*
X258700D03*
X262900D03*
X239600Y142900D03*
X261500Y179000D03*
Y184500D03*
X261000Y190500D03*
X258225Y193963D03*
X266500Y184500D03*
Y190500D03*
X241231Y238869D03*
X236300Y227280D03*
X247500Y233750D03*
X267300Y300600D03*
Y328640D03*
X257340Y338640D03*
X260929Y345571D03*
X248930Y358000D03*
X260646Y499181D03*
X256855Y499154D03*
X265019Y497483D03*
X255487Y512454D03*
X249700Y525737D03*
Y521250D03*
X252238Y574238D03*
X266100Y614400D03*
X265850Y606400D03*
X248500Y583000D03*
X260100Y647400D03*
X259300Y632400D03*
Y639300D03*
X250500Y642500D03*
X265900Y622400D03*
X238100Y643400D03*
X247717Y633233D03*
X259300Y635900D03*
X266906Y775531D03*
X249025Y827374D03*
X255697D03*
X261624D03*
X261811Y878276D03*
X249212D03*
X239764D03*
X255511D03*
X267669Y5500D03*
X271000Y184500D03*
X269849Y308414D03*
X269270Y315759D03*
X297729Y362571D03*
X284200Y465000D03*
X286181Y498546D03*
X291500Y497700D03*
X269000Y504962D03*
X275286Y504392D03*
X280749Y512744D03*
X300835Y578165D03*
Y583165D03*
X301000Y588665D03*
X288835Y593165D03*
X276300Y617350D03*
X281700Y634900D03*
X281100Y651700D03*
X285500Y704900D03*
X294000Y716000D03*
X278406Y716531D03*
X274406Y716598D03*
X270000Y732650D03*
X283161Y730092D03*
X281500Y748500D03*
X282378Y775431D03*
X298500Y752000D03*
X272116Y755592D03*
X298400Y775700D03*
X268296Y827374D03*
X280894D03*
X274222D03*
X286800Y863300D03*
X280800Y863500D03*
X268110Y878276D03*
X280708D03*
X287008D03*
X274410D03*
X329500Y192500D03*
X328000Y197400D03*
X334500Y197500D03*
Y192500D03*
X307300Y221702D03*
X307834Y237966D03*
X328842Y300042D03*
X316420Y331830D03*
X302749Y332651D03*
X326041Y329282D03*
X313875Y364201D03*
X310475Y364193D03*
X316315Y369889D03*
X316205Y376006D03*
X306612Y460177D03*
X307400Y467600D03*
X303440Y475360D03*
X303500Y491000D03*
X322700Y536500D03*
X311406Y535944D03*
X322100Y638500D03*
X322178Y729178D03*
X310016Y729793D03*
X312500Y716500D03*
X313452Y753856D03*
X330000Y754000D03*
X312017Y827374D03*
X318689D03*
X324616D03*
X331288D03*
X306500Y868700D03*
X312000Y868600D03*
X324803Y878276D03*
X331102D03*
X318503D03*
X312500Y878200D03*
X344000Y197500D03*
X339500D03*
X344000Y192500D03*
X339500D03*
X344958Y300740D03*
X344955Y305843D03*
X359500Y448800D03*
X342300Y511600D03*
X350000Y537600D03*
X347100Y605300D03*
X357600Y638300D03*
X366792Y734171D03*
X364275Y723033D03*
X359500Y727335D03*
X342900Y727200D03*
X349813Y827374D03*
X356485D03*
X362411D03*
X343886D03*
X337214D03*
X362599Y878276D03*
X356299D03*
X350000D03*
X343700D03*
X337402D03*
X387669Y5500D03*
X401300Y159800D03*
X401200Y150200D03*
X395100Y449100D03*
X380300Y508700D03*
X401000Y575500D03*
X372000Y579300D03*
X388900Y550400D03*
X386500Y607900D03*
X374275Y722919D03*
X369083Y827374D03*
X384459D03*
X391131D03*
X397057D03*
X378346Y878276D03*
X390944D03*
X397244D03*
X384646D03*
X370500Y878200D03*
X407669Y5500D03*
X427669D03*
X406500Y141700D03*
Y146900D03*
X404170Y326708D03*
X403900Y315492D03*
X416100Y470800D03*
X418900Y529300D03*
X410300Y637500D03*
X416328Y827374D03*
X428926D03*
X422254D03*
X403729D03*
X409656D03*
X416141Y878276D03*
X431889D03*
X422441D03*
X403543D03*
X409843D03*
X447669Y5500D03*
X467669D03*
X461900Y62300D03*
X452600Y114254D03*
X454871Y122291D03*
X457400Y138900D03*
X452500Y153300D03*
X455800Y208300D03*
X461389Y318510D03*
X459200Y369300D03*
X462700D03*
X466700Y388800D03*
X448200Y531400D03*
X443000Y596500D03*
X456335Y835051D03*
X444500Y864450D03*
X438189Y878276D03*
X489261Y-14185D03*
X470200Y62300D03*
X478400D03*
X479700Y90100D03*
X491466Y126683D03*
X494800Y162900D03*
X493186Y272414D03*
X501867Y295490D03*
X486700Y363800D03*
X470200D03*
X490200Y388800D03*
X491860Y382140D03*
X472600Y477700D03*
X487400Y492100D03*
X500800Y567200D03*
X487906Y768598D03*
X491906Y768531D03*
X496061Y781678D03*
X494582Y800500D03*
X483500Y784650D03*
X485300Y808250D03*
X496335Y835051D03*
X480406Y827531D03*
X495878Y827431D03*
X514309Y-315D03*
Y52087D03*
X530057Y67048D03*
Y52087D03*
X530400Y72400D03*
X524000Y43500D03*
X532500Y62900D03*
X536100Y56700D03*
X530057Y106457D03*
Y96969D03*
Y82008D03*
X531400Y102900D03*
X522700D03*
X528700Y91100D03*
X531200Y87900D03*
X535400Y87400D03*
X532900Y92400D03*
X532400Y78200D03*
X521465Y140964D03*
X513876D03*
X532110Y138400D03*
X525000D03*
X506006Y126183D03*
X515348Y163101D03*
X515354Y168998D03*
X505100Y164800D03*
X512600Y186500D03*
X534481Y243676D03*
X518277Y288680D03*
X532921Y298436D03*
X525347Y336979D03*
X512100Y319700D03*
X532499Y315591D03*
X533779Y336979D03*
X507809Y336341D03*
X522209Y333841D03*
X522409Y318441D03*
X518100Y453200D03*
X520500Y519400D03*
X527700Y587500D03*
X522500Y782031D03*
X535178Y781000D03*
X511800Y768300D03*
X528100Y767300D03*
X526274Y806000D03*
X511500Y803000D03*
X533800Y835500D03*
X527941Y864680D03*
X557616Y-315D03*
Y52087D03*
X538915Y67048D03*
X547773D03*
Y52087D03*
X538915D03*
X541200Y73400D03*
X541600Y62600D03*
X544500Y57400D03*
X546800Y46300D03*
X566700Y48700D03*
X570900Y56200D03*
X547773Y106457D03*
X538915Y96969D03*
X547773D03*
X538915Y82008D03*
X547773D03*
X537400Y91000D03*
X540100Y102900D03*
X541700Y92300D03*
X544600Y87300D03*
X538800Y76900D03*
X546800Y76200D03*
X566100Y103100D03*
X543000Y76300D03*
X539031Y136200D03*
X547400Y136170D03*
X560633Y127988D03*
X552800Y140800D03*
X543900Y154800D03*
X550300D03*
X554149Y200229D03*
X541446Y222562D03*
X565063Y256608D03*
Y247608D03*
Y252108D03*
X560318Y267199D03*
Y272199D03*
X560418Y278299D03*
Y283799D03*
Y289299D03*
X560318Y295699D03*
X539450Y322166D03*
X539507Y330787D03*
X554400Y335900D03*
X560531Y358080D03*
X564100Y358100D03*
X556500Y358000D03*
X561781Y346281D03*
X550000Y381000D03*
X542500Y806000D03*
X550186Y827374D03*
X543514D03*
X568711D03*
X556113D03*
X562785D03*
X538000Y878200D03*
X550000Y878276D03*
X562598D03*
X568898D03*
X556300D03*
X544000Y878200D03*
X600923Y-315D03*
Y52087D03*
X573364D03*
X582222D03*
X591080D03*
X573364Y67048D03*
X582222D03*
X591080D03*
X590000Y46200D03*
X579900Y55800D03*
X588000Y57200D03*
X584600Y63200D03*
X575800Y63100D03*
X588000Y72200D03*
X579000Y72300D03*
X573800Y72400D03*
X591080Y106457D03*
X573364D03*
X582222Y82008D03*
X591080D03*
X573364D03*
Y96969D03*
X582222D03*
X591080D03*
X576800Y91600D03*
X584600Y78200D03*
X575500Y78500D03*
X588000Y87100D03*
X579000Y87200D03*
X584500Y93200D03*
X580700Y90900D03*
X572500Y91200D03*
X576300Y103300D03*
X585100D03*
X580800Y76000D03*
X574100Y87800D03*
X579200Y140400D03*
X583640Y140636D03*
X598240Y137800D03*
X572990Y140501D03*
X588955Y140600D03*
X591377Y125797D03*
X597846Y125623D03*
X593000Y152800D03*
X598300Y152850D03*
X597763Y242608D03*
X602763Y240858D03*
X597763Y231608D03*
Y235108D03*
Y239108D03*
X602763Y236608D03*
Y232108D03*
X587100Y234800D03*
X597763Y246108D03*
Y250108D03*
X602763Y245108D03*
Y249608D03*
X605063Y257608D03*
X604170Y337900D03*
X599100Y348700D03*
X597500Y352050D03*
X589500Y361000D03*
X581700Y360700D03*
X573900Y360600D03*
X603500Y371200D03*
X576800Y369200D03*
X584500Y462500D03*
X600400Y538000D03*
X586900Y713200D03*
X593908Y827374D03*
X600580D03*
X587981D03*
X581309D03*
X575383D03*
X594095Y878276D03*
X600393D03*
X587795D03*
X575197D03*
X581497D03*
X616671Y52087D03*
X625529D03*
X634388D03*
X616671Y67048D03*
X625529D03*
X634388D03*
X631100Y72300D03*
X622100Y72400D03*
X628200Y62600D03*
X619200Y62800D03*
X614300Y55800D03*
X620838Y58628D03*
X634100Y46800D03*
X631300Y57100D03*
X616800Y72200D03*
X624700Y61400D03*
X634388Y106457D03*
X616671D03*
X625529Y82008D03*
X634388D03*
X616671D03*
Y96969D03*
X625529D03*
X634388D03*
X611100Y103300D03*
X619600D03*
X628300D03*
X615800Y91200D03*
X624400Y91100D03*
X628000Y93000D03*
X618300Y88000D03*
X628100Y77700D03*
X619400Y77500D03*
X631200Y87200D03*
X624000Y76000D03*
X621900Y87600D03*
X619700Y92100D03*
X629393Y140451D03*
X631940Y137800D03*
X607520Y137780D03*
X605924Y126398D03*
X633900Y149600D03*
X607763Y242608D03*
Y231608D03*
Y235108D03*
Y239108D03*
X619363Y225108D03*
X623363D03*
X611563Y278108D03*
X607763Y246108D03*
Y250108D03*
X607563Y265608D03*
X607463Y270608D03*
X607563Y261108D03*
X609063Y255608D03*
X607563Y276108D03*
Y282108D03*
Y287608D03*
Y293608D03*
X607519Y299497D03*
X611563Y290108D03*
Y284608D03*
X635350Y320850D03*
X606322Y351522D03*
X633000Y356600D03*
Y360500D03*
Y353000D03*
X636500Y356500D03*
X629500D03*
Y371000D03*
X626458Y372521D03*
X616706Y349718D03*
X618680Y346780D03*
X621300Y366900D03*
X609500Y360717D03*
X623000Y382500D03*
X617000D03*
X627600Y685000D03*
X608000Y700800D03*
X613178Y827374D03*
X606506D03*
X638375D03*
X631703D03*
X619105D03*
X625777D03*
X606693Y878276D03*
X619292D03*
X612992D03*
X625590D03*
X631890D03*
X644230Y-315D03*
Y52087D03*
X659978D03*
X668836D03*
X659978Y67048D03*
X668836D03*
X653300Y48600D03*
X665400Y72500D03*
X661100Y73000D03*
X662300Y63300D03*
X656700Y57400D03*
X665696Y57027D03*
X671100Y63400D03*
X659978Y106457D03*
X668836Y82008D03*
X659978D03*
Y96969D03*
X668836D03*
X656400Y102600D03*
X665100Y102700D03*
X660600Y93300D03*
X669400Y93200D03*
X659700Y86400D03*
X662400Y78100D03*
X667500Y76000D03*
X664000Y91100D03*
X671300Y78100D03*
X641159Y137800D03*
X643160Y149600D03*
X666593Y226677D03*
X662593Y223677D03*
X658093D03*
X671124Y210770D03*
X655500Y213500D03*
X672100Y299800D03*
X640532Y318099D03*
X643932Y318104D03*
X639500Y342500D03*
X652254Y336353D03*
X662897Y346873D03*
X663140Y353982D03*
X646884Y355616D03*
X639500Y371000D03*
X653000Y380500D03*
X644100Y488700D03*
X639500Y678500D03*
X657000Y714500D03*
X668500Y700000D03*
X648900Y782500D03*
X666348Y827374D03*
X653750D03*
X660422D03*
X653500Y819100D03*
X647838Y872000D03*
X660236Y878276D03*
X666536D03*
X654000Y878200D03*
X642200Y877900D03*
X687537Y-315D03*
Y52087D03*
X677695D03*
Y67048D03*
X674600Y72200D03*
X676800Y46300D03*
X677695Y106457D03*
Y82008D03*
Y96969D03*
X674300Y102400D03*
X678300Y93100D03*
X674800Y86800D03*
X678063Y238108D03*
X673063D03*
X672927Y219677D03*
X677927D03*
X686063Y230108D03*
X696800Y237900D03*
X682763Y238008D03*
X686063Y224608D03*
X703600Y233700D03*
X687253Y237878D03*
X691753D03*
X698300Y226500D03*
X693800D03*
X685115Y210677D03*
X677000Y299900D03*
X682063Y299108D03*
X683800Y295000D03*
X684063Y285908D03*
Y290408D03*
X689500Y344000D03*
X704500Y343000D03*
X676700Y378800D03*
X687000Y378700D03*
X678500Y684000D03*
X673020Y827374D03*
X698217D03*
X691545D03*
X678947D03*
X685619D03*
X698100Y821600D03*
X703900Y866100D03*
X697700D03*
X704331Y878276D03*
X698031D03*
X691733D03*
X685433D03*
X679134D03*
X672834D03*
X736308Y-7483D03*
X711919Y6754D03*
X729555Y33100D03*
X709120Y35980D03*
X719555Y33100D03*
X735186Y20714D03*
X727265Y52588D03*
X726646Y42651D03*
X721690Y53340D03*
X723501Y82680D03*
X723481Y76780D03*
X723610Y106430D03*
X723569Y100969D03*
X723659Y97292D03*
X723429Y91683D03*
X735157Y97005D03*
X735326Y102660D03*
X723438Y112700D03*
X723638Y118353D03*
X725300Y228700D03*
X730300D03*
X711300D03*
X716300D03*
X716900Y233800D03*
X721400D03*
X730400D03*
X725900D03*
X735400D03*
X707900D03*
X712400D03*
X706800Y290700D03*
X718800Y291000D03*
X714300D03*
X707363Y298108D03*
X718863Y295908D03*
X714363D03*
X723300Y291000D03*
X732300D03*
X727800D03*
X723363Y295908D03*
X732363D03*
X727863D03*
X737300Y291000D03*
X724400Y626500D03*
X735640Y827374D03*
X723041D03*
X729713D03*
X729527Y878276D03*
X735827D03*
X723000Y878200D03*
X752763Y38638D03*
X771600Y24200D03*
X747000Y44300D03*
X762250Y44650D03*
X753500Y96600D03*
X762400Y127600D03*
X753500Y110900D03*
X769400Y111900D03*
X771400Y185919D03*
X766244Y185897D03*
X748237Y194042D03*
X751737D03*
X743500Y362000D03*
X753000Y359000D03*
X743000Y598000D03*
X773435Y827374D03*
X754910D03*
X748238D03*
X742312D03*
X760837D03*
X767509D03*
X754724Y878276D03*
X761024D03*
X767323D03*
X742126D03*
X748426D03*
X788550Y29350D03*
X781500Y85100D03*
X797800Y104500D03*
X776538Y107162D03*
X773900Y138300D03*
X796051Y175147D03*
X796089Y181182D03*
X775397Y179165D03*
Y184215D03*
X792390Y199166D03*
X786463Y199019D03*
X803169Y198850D03*
X797890Y198918D03*
X780800Y545900D03*
X786033Y827374D03*
X780107D03*
X792705D03*
X798632D03*
X805304D03*
X779921Y878276D03*
X786221D03*
X792519D03*
X798819D03*
X805118D03*
X773623D03*
X830773Y9000D03*
X834227D03*
X831592Y34411D03*
X832401Y46472D03*
X831125Y67775D03*
X833900Y467000D03*
X812500Y499400D03*
X836427Y827374D03*
X817902D03*
X811230D03*
X836615Y878276D03*
X830315D03*
X811418D03*
X820000Y878200D03*
X867600Y2500D03*
X855489Y9811D03*
X859300Y9900D03*
X874300Y18875D03*
X858500Y40000D03*
Y32000D03*
X869447Y31024D03*
X843500Y9150D03*
X859200Y47100D03*
X847337Y46563D03*
X851300Y45748D03*
X844900Y85100D03*
X874410Y127953D03*
Y163386D03*
Y202755D03*
Y242125D03*
Y238188D03*
Y257873D03*
Y253936D03*
Y249999D03*
Y246062D03*
X851500Y705500D03*
X852500Y718000D03*
X847500Y717500D03*
X857406Y745598D03*
X861406Y745531D03*
X855500Y775500D03*
X844150Y762150D03*
X858695Y759900D03*
X871000Y776500D03*
X849906Y804531D03*
X865378Y804431D03*
X851890Y789270D03*
X870900Y812104D03*
X855697Y827374D03*
X849025D03*
X843099D03*
X861823Y853696D03*
X849213Y878276D03*
X842913D03*
X856000Y878200D03*
X904262Y14894D03*
X887800Y40100D03*
X880883Y30583D03*
X892745Y9681D03*
X907750Y51750D03*
X894110Y49250D03*
X878800Y49600D03*
X875050Y56250D03*
X895080Y52828D03*
X890000Y97800D03*
X897000Y96700D03*
X894095Y139764D03*
X905906Y124016D03*
Y120079D03*
Y116142D03*
X901969Y124016D03*
X894095D03*
X890158Y127953D03*
X901969D03*
X898032D03*
X894095D03*
X882284Y139764D03*
X886221Y135827D03*
X882284Y131890D03*
X886221Y124016D03*
X878347D03*
X886221Y127953D03*
X882284D03*
X878347D03*
X901969Y167323D03*
X905906D03*
X901969Y171260D03*
X905906D03*
X901969Y175197D03*
X905906D03*
X890158Y163386D03*
X894095Y167323D03*
Y175197D03*
X905906Y159449D03*
X901969D03*
X894095Y155512D03*
Y147638D03*
X882284Y167323D03*
X886221Y163386D03*
X882284D03*
X878347D03*
X886221Y159449D03*
X882284Y155512D03*
X886221Y151575D03*
X882284Y147638D03*
X886221Y143701D03*
X901969Y194881D03*
X905906D03*
X901969Y198818D03*
X905906D03*
X901969Y202755D03*
X905906D03*
X901969Y206692D03*
X905906D03*
X890158Y202755D03*
X898032Y206692D03*
X894095D03*
Y194881D03*
X901969Y179134D03*
X905906D03*
X901969Y190944D03*
X905906D03*
X894095Y183071D03*
X882284Y206692D03*
X886221Y202755D03*
X882284D03*
X878347D03*
X886221Y198818D03*
X882284Y194881D03*
X886221Y190944D03*
Y179134D03*
X901969Y222440D03*
X905906D03*
X901969Y226377D03*
X905906D03*
Y234251D03*
X901969Y230314D03*
X905906D03*
X901969Y234251D03*
X894095Y222440D03*
X890158Y238188D03*
X894095Y242125D03*
Y230314D03*
X901969Y242125D03*
Y210629D03*
X905906D03*
X901969Y214566D03*
X905906D03*
X901969Y218503D03*
X905906D03*
X894095Y214566D03*
X886221Y226377D03*
X882284Y222440D03*
X886221Y242125D03*
X878347D03*
X886221Y238188D03*
X882284D03*
X878347D03*
X886221Y234251D03*
X882284Y230314D03*
X886221Y218503D03*
X882284Y214566D03*
X886221Y210629D03*
X901969Y253936D03*
X894095D03*
X890158Y249999D03*
X905906D03*
X898032D03*
X878347Y253936D03*
X886221D03*
X882284Y249999D03*
X908500Y270500D03*
Y275000D03*
Y267000D03*
X907500Y325000D03*
X902500Y370000D03*
X897000Y370500D03*
X907500Y368000D03*
X900999Y748550D03*
X885400Y743600D03*
X900824Y781531D03*
X895278Y758885D03*
X874887Y759253D03*
X884671Y775500D03*
X885167Y816593D03*
X884412Y835051D03*
X912000Y41000D03*
X927250Y31450D03*
X912000Y45000D03*
X926500Y60050D03*
X930500Y57500D03*
X935000Y97400D03*
X927100Y96900D03*
X941339Y139764D03*
X933465D03*
X921654Y135827D03*
X941339Y124016D03*
Y120079D03*
Y116142D03*
X937402Y124016D03*
X933465Y127953D03*
X929528Y124016D03*
X925591Y127953D03*
X921654Y124016D03*
X917717Y127953D03*
X909843Y135827D03*
X913780Y124016D03*
X909843Y127953D03*
X941339Y175197D03*
Y167323D03*
X933465Y175197D03*
X937402Y171260D03*
X933465Y167323D03*
X937402Y163386D03*
X929528Y171260D03*
X925591Y175197D03*
X921654Y163386D03*
X925591Y167323D03*
X917717D03*
X921654Y171260D03*
X917717Y175197D03*
X929528Y163386D03*
X941339Y159449D03*
X937402Y151575D03*
X933465Y159449D03*
X925591D03*
X921654Y147638D03*
X909843Y163386D03*
X913780D03*
X909843Y167323D03*
X913780D03*
X909843Y171260D03*
X913780D03*
X909843Y175197D03*
X913780D03*
X909843Y147638D03*
X925591Y194881D03*
X921654Y198818D03*
X917717Y202755D03*
X937402Y206692D03*
X941339Y202755D03*
Y194881D03*
X937402Y198818D03*
X933465Y202755D03*
X929528Y206692D03*
X933465Y194881D03*
X929528Y198818D03*
X925591Y202755D03*
X921654Y206692D03*
X917717Y194881D03*
X937402Y179134D03*
X933465Y183071D03*
X929528Y190944D03*
Y179134D03*
X925591Y183071D03*
X921654Y179134D03*
X937402Y190944D03*
X917717Y183071D03*
X921654Y190944D03*
X909843Y194881D03*
X913780D03*
X909843Y198818D03*
X913780D03*
X909843Y202755D03*
X913780D03*
X909843Y206692D03*
X913780D03*
X909843Y179134D03*
X913780D03*
X909843Y183071D03*
Y190944D03*
X913780D03*
X917717Y222440D03*
Y226377D03*
X921654Y222440D03*
Y226377D03*
X917717Y230314D03*
Y234251D03*
X921654Y230314D03*
Y234251D03*
X925591Y230314D03*
Y222440D03*
X933465D03*
X941339D03*
X937402Y226377D03*
X929528D03*
X941339Y238188D03*
Y230314D03*
X937402Y242125D03*
Y234251D03*
X933465Y238188D03*
Y230314D03*
X929528Y242125D03*
Y234251D03*
X925591Y238188D03*
X921654Y242125D03*
X929528Y214566D03*
X933465Y210629D03*
X925591D03*
X917717D03*
X921654Y218503D03*
X925591D03*
X929528D03*
X933465D03*
X937402D03*
X941339D03*
X921654Y214566D03*
X917717Y218503D03*
X937402Y214566D03*
X913780Y226377D03*
X909843Y222440D03*
X913780D03*
X909843Y226377D03*
Y230314D03*
Y234251D03*
X913780Y230314D03*
Y234251D03*
Y242125D03*
X909843D03*
Y214566D03*
Y210629D03*
X913780D03*
X909843Y218503D03*
X913780D03*
X937402Y253936D03*
X929528D03*
X921654D03*
X941339Y249999D03*
X933465D03*
X925591D03*
X917717D03*
X913780Y253936D03*
X909843Y261810D03*
Y257873D03*
Y253936D03*
Y249999D03*
Y246062D03*
X909000Y279000D03*
X909500Y283000D03*
Y338000D03*
X909000Y353600D03*
X908700Y347300D03*
X938898Y640169D03*
X916319Y678588D03*
Y658588D03*
Y698588D03*
Y738588D03*
Y718588D03*
Y778588D03*
Y758588D03*
Y798588D03*
Y818588D03*
X969100Y14600D03*
X976066Y26581D03*
X971466Y26681D03*
X942500Y30100D03*
X975086Y61900D03*
X970000Y61050D03*
X952500Y75100D03*
X956500Y108000D03*
X949500Y103000D03*
Y97500D03*
X953149Y135827D03*
X968897Y139764D03*
X953149Y124016D03*
Y120079D03*
Y116142D03*
X972834Y124016D03*
X968897Y127953D03*
X964960Y124016D03*
X961023Y127953D03*
X957086Y124016D03*
X953149Y167323D03*
X957086Y163386D03*
X949212Y171260D03*
Y163386D03*
X972834Y171260D03*
X968897Y175197D03*
X972834Y163386D03*
X968897Y167323D03*
X964960Y171260D03*
X961023Y175197D03*
Y167323D03*
X964960Y163386D03*
X953149Y175197D03*
X957086Y171260D03*
X953149Y159449D03*
X949212Y151575D03*
X972834Y147638D03*
X968897Y159449D03*
X961023D03*
Y147638D03*
X964960Y198818D03*
X961023Y202755D03*
X957086Y206692D03*
X968897Y194881D03*
X953149D03*
X949212Y198818D03*
Y206692D03*
X953149Y202755D03*
X961023Y194881D03*
X957086Y198818D03*
X972834Y206692D03*
Y198818D03*
X968897Y202755D03*
X964960Y206692D03*
X972834Y190944D03*
X964960Y179134D03*
X961023Y183071D03*
X957086Y190944D03*
X953149Y183071D03*
X957086Y179134D03*
X949212D03*
X964960Y190944D03*
X968897Y183071D03*
X972834Y179134D03*
Y222440D03*
Y226377D03*
Y230314D03*
Y234251D03*
X968897Y230314D03*
Y222440D03*
X953149D03*
X961023D03*
X972834Y242125D03*
X949212Y226377D03*
X964960D03*
X957086D03*
X953149Y238188D03*
Y230314D03*
X949212Y242125D03*
Y234251D03*
X968897Y238188D03*
X964960Y242125D03*
Y234251D03*
X961023Y238188D03*
Y230314D03*
X957086Y242125D03*
Y234251D03*
X949212Y214566D03*
X953149Y210629D03*
X968897D03*
X964960Y214566D03*
X972834Y218503D03*
X949212D03*
X953149D03*
X957086Y214566D03*
X961023Y210629D03*
X972834Y214566D03*
X957086Y218503D03*
X961023D03*
X964960D03*
X968897D03*
X972834Y253936D03*
X949212Y261810D03*
Y257873D03*
Y253936D03*
X964960D03*
X957086D03*
X953149Y249999D03*
X949212D03*
Y246062D03*
X968897Y249999D03*
X961023D03*
X957800Y570300D03*
X958898Y640169D03*
X976500Y4500D03*
X980100Y14500D03*
X1000985Y29307D03*
X1007921Y39585D03*
X980566Y26581D03*
X985315Y14425D03*
X997385Y29307D03*
X992396Y45073D03*
X1008267Y135827D03*
Y127953D03*
Y124016D03*
X984645Y135827D03*
X1000393Y139764D03*
X992519Y127953D03*
Y124016D03*
X988582Y127953D03*
Y124016D03*
Y120079D03*
Y116142D03*
X984645Y127953D03*
X980708Y124016D03*
X996456Y127953D03*
X1000393Y124016D03*
Y127953D03*
X1004330D03*
X976771D03*
X1008267Y163386D03*
Y171260D03*
Y159449D03*
Y143701D03*
Y151575D03*
X980708Y163386D03*
X984645D03*
X988582Y167323D03*
X992519D03*
X980708D03*
X984645D03*
X988582Y171260D03*
X992519D03*
X980708D03*
X984645D03*
X988582Y175197D03*
X992519D03*
X984645D03*
X1000393Y167323D03*
X1004330Y163386D03*
X1000393Y175197D03*
X988582Y159449D03*
X992519D03*
X984645Y147638D03*
X1000393D03*
Y155512D03*
X976771Y167323D03*
Y175197D03*
X1008267Y202755D03*
Y198818D03*
Y190944D03*
Y179134D03*
X980708Y198818D03*
X988582Y194881D03*
X992519D03*
X980708D03*
X984645D03*
X988582Y198818D03*
X992519D03*
X984645D03*
X988582Y202755D03*
X992519D03*
X980708D03*
X984645D03*
X988582Y206692D03*
X992519D03*
X980708D03*
X984645D03*
X1000393D03*
X996456D03*
X1004330Y202755D03*
X1000393Y194881D03*
X988582Y179134D03*
X992519D03*
X988582Y190944D03*
X992519D03*
X980708D03*
X984645D03*
X980708Y179134D03*
X984645D03*
Y183071D03*
X1000393D03*
X976771Y202755D03*
Y194881D03*
Y183071D03*
X1008267Y226377D03*
Y242125D03*
Y238188D03*
Y234251D03*
Y218503D03*
Y210629D03*
X1000393Y222440D03*
X988582D03*
X992519D03*
X980708D03*
X984645D03*
X988582Y226377D03*
X992519D03*
X984645D03*
X980708D03*
X988582Y230314D03*
X992519D03*
Y234251D03*
X980708Y230314D03*
Y234251D03*
X984645Y230314D03*
Y234251D03*
X988582D03*
X1000393Y230314D03*
X1004330Y238188D03*
X1000393Y242125D03*
X980708D03*
X984645D03*
X992519D03*
X984645Y214566D03*
X988582Y210629D03*
X992519D03*
X980708D03*
X984645D03*
X988582Y214566D03*
X992519D03*
X988582Y218503D03*
X992519D03*
X980708D03*
X984645D03*
X1000393Y214566D03*
X976771Y222440D03*
Y226377D03*
Y230314D03*
Y234251D03*
Y210629D03*
Y218503D03*
X1008267Y253936D03*
X980708D03*
X984645D03*
Y257873D03*
Y261810D03*
X992519Y253936D03*
X1000393D03*
X984645Y246062D03*
Y249999D03*
X988582D03*
X996456D03*
X1004330D03*
X976771D03*
X982500Y271500D03*
Y275500D03*
X982000Y267500D03*
X983500Y279500D03*
Y283500D03*
X1006100Y528700D03*
X977500Y550000D03*
X978898Y640169D03*
X994248Y665818D03*
Y685818D03*
Y705818D03*
Y745818D03*
Y725818D03*
Y765818D03*
Y805818D03*
Y785818D03*
X1025700Y7600D03*
X1024330Y34379D03*
X1040218Y32140D03*
X1010229Y19022D03*
X1022300Y13900D03*
X1035783Y51473D03*
X1017863Y45056D03*
X1021751Y117469D03*
X1012204Y131890D03*
Y139764D03*
Y127953D03*
X1016141Y124016D03*
X1020078Y127953D03*
X1016141D03*
X1012204Y167323D03*
Y163386D03*
X1016141D03*
X1020078D03*
X1012204Y175197D03*
Y147638D03*
Y155512D03*
Y206692D03*
Y202755D03*
Y194881D03*
X1016141Y202755D03*
X1020078D03*
X1012204Y183071D03*
Y222440D03*
Y238188D03*
Y230314D03*
X1016141Y242125D03*
X1020078D03*
X1016141Y238188D03*
X1020078D03*
X1012204Y214566D03*
X1020078Y257873D03*
X1016141Y253936D03*
X1020078D03*
X1012204Y249999D03*
X1020078D03*
Y246062D03*
X1012600Y476700D03*
X1022600Y542100D03*
X1017800Y572700D03*
X1043300Y631300D03*
X1041500Y682000D03*
X1041900Y658100D03*
X1039577Y827374D03*
X1024004Y855893D03*
X1033464Y878276D03*
X1039764D03*
X1069261Y-14185D03*
X1049261D03*
X1061253Y17487D03*
X1062470Y31823D03*
X1062433Y37099D03*
X1056049Y18396D03*
X1061153Y27488D03*
X1046200Y24500D03*
X1054835Y40386D03*
X1072140Y16447D03*
X1047429Y15229D03*
X1054210Y53370D03*
X1054090Y58470D03*
X1068315Y56120D03*
X1068390Y61611D03*
X1074103Y44988D03*
X1047000Y644000D03*
X1045000Y617500D03*
X1067000Y711000D03*
X1062500Y738000D03*
X1058500Y758000D03*
X1058847Y827374D03*
X1052175D03*
X1046249D03*
X1064774D03*
X1071446D03*
X1046063Y878276D03*
X1071260D03*
X1064961D03*
X1058661D03*
X1052363D03*
X1089261Y-14185D03*
X1103424Y67690D03*
X1110664Y78483D03*
X1103253Y76910D03*
X1079500Y631000D03*
X1080000Y650500D03*
X1081000Y670000D03*
X1084044Y827374D03*
X1077372D03*
X1102569D03*
X1109241D03*
X1089970D03*
X1096642D03*
X1090158Y878276D03*
X1083858D03*
X1077560D03*
X1096456D03*
X1102756D03*
X1109055D03*
X1116671Y-315D03*
Y52087D03*
X1132419Y67048D03*
X1141277D03*
Y52087D03*
X1132419D03*
X1127300Y46300D03*
X1122800Y55100D03*
X1132100Y56300D03*
X1131900Y70700D03*
X1140900Y71100D03*
X1141900Y63300D03*
X1132419Y106457D03*
Y96969D03*
X1141277D03*
X1132419Y82008D03*
X1141277D03*
X1142418Y78638D03*
X1131800Y85600D03*
X1141200Y86800D03*
X1126400Y92200D03*
X1143500Y93300D03*
X1123000Y99200D03*
X1131880Y100377D03*
X1134800Y93300D03*
X1116933Y85243D03*
X1122001Y126574D03*
Y136874D03*
X1135150Y137851D03*
X1126500Y222500D03*
X1135750Y228750D03*
X1140364Y827374D03*
X1121839D03*
X1115167D03*
X1127766D03*
X1134438D03*
X1140552Y878276D03*
X1115355D03*
X1127953D03*
X1134252D03*
X1121653D03*
X1159978Y-315D03*
Y52087D03*
X1175726D03*
Y67048D03*
X1150135D03*
Y52087D03*
X1175300Y71100D03*
X1175100Y55700D03*
X1166500Y56200D03*
X1171700Y45900D03*
X1149100Y46300D03*
X1150700Y63300D03*
X1175726Y106457D03*
X1150135D03*
X1175726Y82008D03*
Y96969D03*
X1150135D03*
Y82008D03*
X1148900Y75900D03*
X1168400Y103000D03*
X1177000Y102800D03*
X1176200Y92900D03*
X1178100Y78000D03*
X1175200Y85900D03*
X1151492Y78668D03*
X1164857Y138505D03*
X1154557D03*
X1145450Y137851D03*
X1175851Y142410D03*
X1150250Y228750D03*
X1171300Y215700D03*
X1166300D03*
X1175999D03*
X1168000Y280000D03*
X1173000D03*
X1177500D03*
X1161700Y818500D03*
X1159634Y827374D03*
X1152962D03*
X1147036D03*
X1175010D03*
X1174900Y818300D03*
X1159448Y878276D03*
X1153150D03*
X1173623Y878200D03*
X1146850Y878276D03*
X1165748D03*
X1203285Y-315D03*
Y52087D03*
X1184584D03*
X1193442D03*
X1184584Y67048D03*
X1193442D03*
X1185200Y72600D03*
X1210511Y52300D03*
X1193555Y61875D03*
X1183884Y61598D03*
X1188200Y61600D03*
X1192300Y46100D03*
X1184100Y56100D03*
X1193442Y106457D03*
X1184584Y82008D03*
X1193442D03*
X1184584Y96969D03*
X1193442D03*
X1193900Y78000D03*
X1211500Y102900D03*
X1194000Y93200D03*
X1185800Y102900D03*
X1185100Y93000D03*
X1187100Y77900D03*
X1184800Y87200D03*
X1202410Y142850D03*
X1193845Y137855D03*
X1184629Y137740D03*
X1185070Y142384D03*
X1210391Y156730D03*
X1200391Y156779D03*
X1193192Y142970D03*
X1190300Y215700D03*
X1185300D03*
X1208800D03*
X1203800D03*
X1180601D03*
X1199300D03*
X1194500D03*
X1187000Y280000D03*
X1192000D03*
X1205500D03*
X1210500D03*
X1182500D03*
X1201000D03*
X1196200D03*
X1205500Y334400D03*
X1194280Y827374D03*
X1187608D03*
X1181682D03*
X1200735Y864273D03*
X1194063D03*
X1200394Y878276D03*
X1194094D03*
X1187796D03*
X1181496D03*
X1246592Y-315D03*
Y52087D03*
X1219033D03*
X1227891D03*
X1236750D03*
X1219033Y67048D03*
X1227891D03*
X1236750D03*
X1231400Y58300D03*
X1215400Y57600D03*
X1216300Y72900D03*
X1235800Y46400D03*
X1228000Y57000D03*
X1218600Y56000D03*
X1214700Y46000D03*
X1221200Y63400D03*
X1230300Y63200D03*
X1228900Y72900D03*
X1236750Y106457D03*
X1219033D03*
X1227891Y82008D03*
X1236750D03*
X1219033D03*
Y96969D03*
X1227891D03*
X1236750D03*
X1230000Y78800D03*
X1221300Y78400D03*
X1219200Y87000D03*
X1229100Y87900D03*
X1232500Y90900D03*
X1229900Y103100D03*
X1228300Y93100D03*
X1219500Y93300D03*
X1220100Y102700D03*
X1219138Y137928D03*
X1227999Y142465D03*
X1236692Y137720D03*
X1237219Y142420D03*
X1228359Y137960D03*
X1229000Y210500D03*
X1242500Y209000D03*
X1232000Y194500D03*
X1237000D03*
X1226500Y201500D03*
Y194500D03*
X1244500D03*
X1214800Y215700D03*
X1227000Y279000D03*
X1242000D03*
X1232000Y292000D03*
X1237000D03*
X1227000Y285500D03*
X1244500Y292000D03*
X1242000Y343000D03*
X1235400Y364400D03*
X1213400Y355400D03*
X1214100Y469800D03*
X1237800Y524500D03*
X1232300Y568900D03*
X1238375Y827374D03*
X1231703D03*
X1219105D03*
X1225777D03*
X1244302D03*
X1217717Y878076D03*
X1225590Y878276D03*
X1231890D03*
X1244489D03*
X1238189D03*
X1262340Y52087D03*
X1271198D03*
X1280057D03*
X1262340Y67048D03*
X1271198D03*
X1280057D03*
X1261900Y71039D03*
X1265500Y61900D03*
X1272200Y72900D03*
X1275200Y61200D03*
X1269900Y61100D03*
X1279100Y46300D03*
X1272200Y57900D03*
X1258400Y45900D03*
X1254500Y51100D03*
X1280057Y106457D03*
X1262340D03*
X1271198Y82008D03*
X1280057D03*
X1262340D03*
Y96969D03*
X1271198D03*
X1280057D03*
X1271300Y77100D03*
X1273200Y103200D03*
X1256000Y103300D03*
X1263200Y102700D03*
X1270300Y91100D03*
X1262800Y93100D03*
X1254200Y96300D03*
X1275500Y91000D03*
X1272700Y88000D03*
X1265200Y77400D03*
X1261900Y86000D03*
X1275800Y75900D03*
X1252768Y141181D03*
X1278160Y140547D03*
X1257899Y142881D03*
X1245910Y137810D03*
X1273068Y140514D03*
X1262880Y142909D03*
X1247500Y209000D03*
X1252500Y194500D03*
X1263000Y210307D03*
X1257500Y194500D03*
X1263000Y202000D03*
X1262500Y194500D03*
X1247000Y279000D03*
X1262500Y279500D03*
X1252000Y292000D03*
X1257000D03*
X1262500Y286000D03*
X1258500Y335500D03*
X1266500D03*
X1273500Y397000D03*
X1257500D03*
X1254000D03*
X1259200Y471800D03*
X1259000Y680000D03*
X1265000Y672000D03*
X1253500D03*
X1278000Y689000D03*
X1263572Y827374D03*
X1269498D03*
X1276170D03*
X1256900D03*
X1250974D03*
X1263386Y878276D03*
X1275984D03*
X1257087D03*
X1269686D03*
X1250787D03*
X1289899Y-315D03*
Y52087D03*
X1291660Y140257D03*
X1297360Y140172D03*
X1301749Y125479D03*
X1282189Y144361D03*
X1287637Y144386D03*
X1297668Y155524D03*
X1290870Y186285D03*
X1311181Y186548D03*
X1297500Y351800D03*
X1291600Y495200D03*
X1296400Y542400D03*
X1294700Y593400D03*
X1302128Y674067D03*
X1306128Y674000D03*
X1285000Y694000D03*
X1280500Y706000D03*
X1310376Y687205D03*
X1301728Y711200D03*
X1310100Y732900D03*
X1294628Y733000D03*
X1304800Y811900D03*
X1288768Y827374D03*
X1282096D03*
X1307294D03*
X1301800Y878100D03*
X1294268Y872169D03*
X1288582Y878276D03*
X1282284D03*
X1307481D03*
X1324845Y130527D03*
X1325429Y148270D03*
X1327782Y192579D03*
Y200579D03*
Y207579D03*
X1328411Y237679D03*
X1327782Y215579D03*
Y221579D03*
X1327841Y228639D03*
X1332683Y240409D03*
X1328356Y242091D03*
X1328317Y246291D03*
X1332683Y244609D03*
Y248809D03*
X1337000Y263250D03*
X1332000Y261500D03*
Y265000D03*
Y268500D03*
Y272500D03*
Y257500D03*
Y254000D03*
X1342000D03*
Y257500D03*
Y261500D03*
Y265000D03*
Y268500D03*
Y272500D03*
X1337000Y267500D03*
Y272000D03*
Y259000D03*
Y254500D03*
X1322250Y282250D03*
X1345850Y676750D03*
X1326250Y669550D03*
X1333500Y709500D03*
X1323076Y686999D03*
X1338200Y689800D03*
X1315546Y709500D03*
X1341400Y686900D03*
X1326661Y740700D03*
X1345088Y827374D03*
X1332490D03*
X1339162D03*
X1326564D03*
X1319892D03*
X1313966D03*
X1320079Y878276D03*
X1345276D03*
X1332678D03*
X1338976D03*
X1326378D03*
X1313779D03*
X1368028Y175745D03*
X1366672Y210312D03*
X1375196Y217203D03*
X1367042Y223895D03*
X1375359Y230110D03*
X1372000Y240500D03*
X1368300Y267800D03*
X1358662Y275485D03*
X1372000Y245300D03*
Y249500D03*
X1369700Y424600D03*
X1366000Y472900D03*
X1363900Y537600D03*
X1361800Y596800D03*
X1358700Y655700D03*
X1348500Y713000D03*
X1377000Y725000D03*
X1378000Y806900D03*
X1369925Y835051D03*
X1351760Y827374D03*
X1357886Y864246D03*
X1352200Y878400D03*
X1394500Y139626D03*
Y119626D03*
Y159626D03*
Y199626D03*
Y179626D03*
X1381568Y180579D03*
X1394500Y239626D03*
Y219626D03*
Y259626D03*
Y299626D03*
Y279626D03*
Y339626D03*
Y319626D03*
Y359626D03*
Y399626D03*
Y379626D03*
Y439626D03*
Y419626D03*
Y479626D03*
Y459626D03*
Y499626D03*
Y539626D03*
Y519626D03*
Y579626D03*
Y559626D03*
Y599626D03*
Y639626D03*
Y619626D03*
Y679626D03*
Y659626D03*
Y699626D03*
Y739626D03*
Y719626D03*
Y759626D03*
Y779626D03*
Y799626D03*
Y819626D03*
X1389925Y835051D03*
G54D39*
X911616Y13778D03*
G54D33*
X501742Y215594D03*
G54D37*
X819291Y265354D03*
Y285354D03*
G54D10*
X700Y19100D03*
X16200Y120100D03*
X27200Y821800D03*
X33800Y872600D03*
X1384200Y122800D03*
X1373200Y823500D03*
X1415100Y-36700D03*
X1389800Y879000D03*
G54D16*
X39370Y801181D03*
X1360630Y135826D03*
Y801181D03*
G54D22*
X122165Y142874D03*
X173897D03*
G54D17*
X42587Y151614D03*
X80579D03*
G54D30*
X336417Y21260D03*
X293110Y55906D03*
X336417Y90551D03*
X789850Y236220D03*
Y283464D03*
X1376968Y21260D03*
X1333661Y55906D03*
X1376968Y90551D03*
G54D15*
X25050Y716900D03*
X47300Y704400D03*
X42300Y704900D03*
X59300Y734900D03*
X54300Y729900D03*
X49300Y734900D03*
X54300Y739900D03*
Y734900D03*
X71500Y297900D03*
X77100Y303800D03*
X65400D03*
X65500Y291900D03*
X77500D03*
X89400Y749200D03*
X89300Y736300D03*
X89800Y753400D03*
X191000Y246500D03*
X534481Y286876D03*
G54D35*
X535962Y37520D03*
X579269D03*
X622577D03*
X665884D03*
X1138324D03*
X1181631D03*
X1224939D03*
X1268246D03*
G54D13*
X26977Y151614D03*
X96189D03*
G54D27*
X161811Y153543D03*
%LPC*%
G75*
G54D41*
G01X127746Y-260199D02*
X95746D01*
G01X127746Y-276199D02*
Y-356199D01*
G01D02*
X1310146D01*
G01X127746Y-311699D02*
X1310146D01*
G01X123746Y-260199D02*
G02I-12000J0D01*
G01X118596D02*
G02I-6850J0D01*
G01X111746Y-276199D02*
Y-244199D01*
G01X127746Y-276199D02*
X1310146D01*
G01X522646D02*
Y-356199D01*
G01X660146Y-276199D02*
Y-356199D01*
G01X775146Y-276199D02*
Y-356199D01*
G01X942646Y-276199D02*
Y-356199D01*
G01X1112646Y-276199D02*
Y-356199D01*
G01X1310146Y-276199D02*
Y-356199D01*
G01X1342146Y-260199D02*
X1310146D01*
G01X1338146D02*
G02I-12000J0D01*
G01X1332996D02*
G02I-6850J0D01*
G01X1326146Y-276199D02*
Y-244199D01*
G54D42*
G01X145579Y-328699D02*
Y-346199D01*
X154313D01*
G01X167446Y-334533D02*
Y-346199D01*
G01Y-329866D02*
X167009Y-329574D01*
Y-328991D01*
X167446Y-328699D01*
X167883Y-328991D01*
Y-329574D01*
X167446Y-329866D01*
G01X181889Y-350574D02*
X183418Y-351741D01*
X185164Y-352032D01*
X186692Y-351741D01*
X188003Y-350283D01*
X188876Y-348241D01*
Y-334533D01*
G01Y-336866D02*
X188003Y-335699D01*
X186692Y-334824D01*
X185164Y-334533D01*
X183418Y-335116D01*
X182326Y-336282D01*
X181452Y-338324D01*
X181016Y-340366D01*
X181234Y-342116D01*
X182108Y-344158D01*
X183418Y-345616D01*
X185164Y-346199D01*
X186474Y-345907D01*
X188003Y-344741D01*
X188876Y-343575D01*
G01X198734Y-346199D02*
Y-328699D01*
G01Y-337157D02*
X199826Y-335699D01*
X200918Y-334824D01*
X202664Y-334533D01*
X203974Y-334824D01*
X205503Y-335991D01*
X206158Y-337741D01*
Y-346199D01*
G01X219946Y-328699D02*
Y-346199D01*
G01X216889Y-334533D02*
X223003D01*
G01X233734Y-346199D02*
Y-334533D01*
G01Y-337449D02*
X234608Y-335991D01*
X235918Y-334824D01*
X237664Y-334533D01*
X239192Y-334824D01*
X240503Y-335991D01*
X241158Y-338032D01*
Y-346199D01*
G01X254946Y-334533D02*
Y-346199D01*
G01Y-329866D02*
X254509Y-329574D01*
Y-328991D01*
X254946Y-328699D01*
X255383Y-328991D01*
Y-329574D01*
X254946Y-329866D01*
G01X268734Y-346199D02*
Y-334533D01*
G01Y-337449D02*
X269608Y-335991D01*
X270918Y-334824D01*
X272664Y-334533D01*
X274192Y-334824D01*
X275503Y-335991D01*
X276158Y-338032D01*
Y-346199D01*
G01X286889Y-350574D02*
X288418Y-351741D01*
X290164Y-352032D01*
X291692Y-351741D01*
X293003Y-350283D01*
X293876Y-348241D01*
Y-334533D01*
G01Y-336866D02*
X293003Y-335699D01*
X291692Y-334824D01*
X290164Y-334533D01*
X288418Y-335116D01*
X287326Y-336282D01*
X286452Y-338324D01*
X286016Y-340366D01*
X286234Y-342116D01*
X287108Y-344158D01*
X288418Y-345616D01*
X290164Y-346199D01*
X291474Y-345907D01*
X293003Y-344741D01*
X293876Y-343575D01*
G01X320579Y-346199D02*
Y-328699D01*
X325819D01*
X327566Y-329574D01*
X328876Y-331616D01*
X329313Y-333949D01*
X328876Y-336282D01*
X327784Y-338032D01*
X325819Y-338908D01*
X320579D01*
G01X346813Y-346199D02*
X338079D01*
Y-328699D01*
X346813D01*
G01X343319Y-337157D02*
X338079D01*
G01X361692Y-336866D02*
X362566Y-335991D01*
X363221Y-334533D01*
X363658Y-332490D01*
X363221Y-330741D01*
X362348Y-329574D01*
X360819Y-328699D01*
X354924D01*
Y-346199D01*
X362129D01*
X363658Y-345033D01*
X364531Y-343282D01*
X364968Y-341241D01*
X364531Y-339199D01*
X363221Y-337449D01*
X361692Y-336866D01*
X354924D01*
G01X390579Y-346199D02*
Y-328699D01*
X395819D01*
X397566Y-329574D01*
X398876Y-331616D01*
X399313Y-333949D01*
X398876Y-336282D01*
X397784Y-338032D01*
X395819Y-338908D01*
X390579D01*
G01X406769Y-346199D02*
Y-328699D01*
X412446Y-343282D01*
X418123Y-328699D01*
Y-346199D01*
G01X434749Y-330158D02*
X433439Y-329282D01*
X431911Y-328699D01*
X430164D01*
X428199Y-329574D01*
X426671Y-331032D01*
X425579Y-332783D01*
X424706Y-335699D01*
X424487Y-338324D01*
X424924Y-340949D01*
X425579Y-342699D01*
X426889Y-344449D01*
X428418Y-345616D01*
X429946Y-346199D01*
X431474D01*
X433003Y-345616D01*
X434313Y-344741D01*
X435405Y-343575D01*
G01X460579Y-346199D02*
Y-328699D01*
X465819D01*
X467566Y-329574D01*
X468876Y-331616D01*
X469313Y-333949D01*
X468876Y-336282D01*
X467784Y-338032D01*
X465819Y-338908D01*
X460579D01*
G01X476987Y-328699D02*
X482446Y-346199D01*
X487905Y-328699D01*
G01X499946D02*
Y-346199D01*
G01X494924Y-328699D02*
X504968D01*
G01X284269Y-301199D02*
Y-283699D01*
X289946Y-298282D01*
X295623Y-283699D01*
Y-301199D01*
G01X307446D02*
X306136Y-300907D01*
X304826Y-299741D01*
X303952Y-297699D01*
X303516Y-295366D01*
X303952Y-293032D01*
X304826Y-290991D01*
X306136Y-289824D01*
X307446Y-289533D01*
X308756Y-289824D01*
X310066Y-290991D01*
X310939Y-293032D01*
X311158Y-295366D01*
X310939Y-297699D01*
X310066Y-299741D01*
X308756Y-300907D01*
X307446Y-301199D01*
G01X328876Y-283699D02*
Y-301199D01*
G01Y-298575D02*
X328003Y-300033D01*
X326692Y-300907D01*
X325164Y-301199D01*
X323418Y-300616D01*
X322108Y-299158D01*
X321234Y-297408D01*
X321016Y-295366D01*
X321234Y-293324D01*
X322108Y-291574D01*
X323418Y-290116D01*
X325164Y-289533D01*
X326692Y-289824D01*
X327784Y-290408D01*
X328876Y-291574D01*
G01X339171Y-293324D02*
X346158D01*
X345503Y-291282D01*
X344411Y-290116D01*
X342883Y-289533D01*
X341354Y-289824D01*
X340044Y-290699D01*
X339171Y-292741D01*
X338734Y-294491D01*
Y-296241D01*
X339171Y-297991D01*
X340263Y-299741D01*
X341573Y-300907D01*
X343101Y-301199D01*
X344629Y-300616D01*
X346158Y-298866D01*
G01X359946Y-301199D02*
Y-283699D01*
G01X556346Y-346199D02*
Y-328699D01*
X553726Y-332199D01*
G01Y-346199D02*
X558966D01*
G01X569043Y-343575D02*
X570352Y-345033D01*
X571881Y-345907D01*
X573846Y-346199D01*
X575811Y-345616D01*
X577339Y-344449D01*
X578431Y-342408D01*
X578649Y-340074D01*
X578213Y-337741D01*
X577121Y-336282D01*
X575592Y-335116D01*
X574064Y-334824D01*
X572536Y-335116D01*
X570571Y-336282D01*
X571226Y-328699D01*
X577121D01*
G01X591346Y-346199D02*
Y-328699D01*
X588726Y-332199D01*
G01Y-346199D02*
X593966D01*
G01X608846Y-328699D02*
X607099Y-329282D01*
X605789Y-330741D01*
X604916Y-332490D01*
X604261Y-334824D01*
X604043Y-337449D01*
X604261Y-340074D01*
X604916Y-342408D01*
X605789Y-344158D01*
X607099Y-345616D01*
X608846Y-346199D01*
X610592Y-345616D01*
X611903Y-344158D01*
X612776Y-342408D01*
X613431Y-340074D01*
X613649Y-337449D01*
X613431Y-334824D01*
X612776Y-332490D01*
X611903Y-330741D01*
X610592Y-329282D01*
X608846Y-328699D01*
G01X621543Y-343575D02*
X622852Y-345033D01*
X624381Y-345907D01*
X626346Y-346199D01*
X628311Y-345616D01*
X629839Y-344449D01*
X630931Y-342408D01*
X631149Y-340074D01*
X630713Y-337741D01*
X629621Y-336282D01*
X628092Y-335116D01*
X626564Y-334824D01*
X625036Y-335116D01*
X623071Y-336282D01*
X623726Y-328699D01*
X629621D01*
G01X543229Y-301199D02*
Y-283699D01*
X548469D01*
X550216Y-284574D01*
X551526Y-286616D01*
X551963Y-288949D01*
X551526Y-291282D01*
X550434Y-293032D01*
X548469Y-293908D01*
X543229D01*
G01X569899Y-285158D02*
X568589Y-284282D01*
X567061Y-283699D01*
X565314D01*
X563349Y-284574D01*
X561821Y-286032D01*
X560729Y-287783D01*
X559856Y-290699D01*
X559637Y-293324D01*
X560074Y-295949D01*
X560729Y-297699D01*
X562039Y-299449D01*
X563568Y-300616D01*
X565096Y-301199D01*
X566624D01*
X568153Y-300616D01*
X569463Y-299741D01*
X570555Y-298575D01*
G01X584342Y-291866D02*
X585216Y-290991D01*
X585871Y-289533D01*
X586308Y-287490D01*
X585871Y-285741D01*
X584998Y-284574D01*
X583469Y-283699D01*
X577574D01*
Y-301199D01*
X584779D01*
X586308Y-300033D01*
X587181Y-298282D01*
X587618Y-296241D01*
X587181Y-294199D01*
X585871Y-292449D01*
X584342Y-291866D01*
X577574D01*
G01X593546Y-307032D02*
X606646D01*
G01X612574Y-301199D02*
Y-283699D01*
X622618Y-301199D01*
Y-283699D01*
G01X635096Y-301199D02*
X633349Y-300907D01*
X631821Y-299741D01*
X630511Y-297991D01*
X629637Y-295949D01*
X629201Y-293616D01*
Y-291282D01*
X629637Y-288949D01*
X630511Y-286907D01*
X631821Y-285158D01*
X633349Y-283991D01*
X635096Y-283699D01*
X636842Y-283991D01*
X638371Y-285158D01*
X639681Y-286907D01*
X640555Y-288949D01*
X640991Y-291282D01*
Y-293616D01*
X640555Y-295949D01*
X639681Y-297991D01*
X638371Y-299741D01*
X636842Y-300907D01*
X635096Y-301199D01*
G01X685937Y-283699D02*
X691396Y-301199D01*
X696855Y-283699D01*
G01X713263Y-301199D02*
X704529D01*
Y-283699D01*
X713263D01*
G01X709769Y-292157D02*
X704529D01*
G01X722029Y-301199D02*
Y-283699D01*
X727488D01*
X729234Y-284574D01*
X730326Y-285741D01*
X730763Y-288074D01*
X730326Y-290408D01*
X729016Y-291866D01*
X727488Y-292741D01*
X722029D01*
G01X727488D02*
X730763Y-301199D01*
G01X743896Y-301782D02*
X743459Y-301491D01*
Y-300907D01*
X743896Y-300616D01*
X744333Y-300907D01*
Y-301491D01*
X743896Y-301782D01*
G01X717646Y-346199D02*
Y-328699D01*
X715026Y-332199D01*
G01Y-346199D02*
X720266D01*
G01X819479Y-328699D02*
Y-346199D01*
X828213D01*
G01X837198Y-331616D02*
X838508Y-329866D01*
X840036Y-328991D01*
X841783Y-328699D01*
X843966Y-329282D01*
X845494Y-330741D01*
X845931Y-332490D01*
X845713Y-334241D01*
X844839Y-335699D01*
X840473Y-338616D01*
X838508Y-340657D01*
X837198Y-343575D01*
X836761Y-346199D01*
X845931D01*
G01X860156Y-337449D02*
X864523D01*
Y-342699D01*
X863213Y-344449D01*
X861684Y-345616D01*
X859501Y-346199D01*
X857318Y-345616D01*
X855789Y-344449D01*
X854479Y-342699D01*
X853606Y-340657D01*
X853169Y-338324D01*
Y-336282D01*
X853606Y-334533D01*
X854479Y-332490D01*
X855789Y-330741D01*
X857099Y-329574D01*
X858846Y-328699D01*
X860374D01*
X862121Y-329282D01*
X863431Y-330449D01*
G01X871324Y-346199D02*
Y-328699D01*
X881368Y-346199D01*
Y-328699D01*
G01X889043Y-346199D02*
Y-328699D01*
X893409D01*
X895156Y-329574D01*
X896466Y-330741D01*
X897558Y-332490D01*
X898431Y-334533D01*
X898649Y-337449D01*
X898431Y-340366D01*
X897558Y-342408D01*
X896466Y-344158D01*
X895156Y-345324D01*
X893409Y-346199D01*
X889043D01*
G01X819479Y-283699D02*
Y-301199D01*
X828213D01*
G01X845276D02*
Y-289533D01*
G01Y-291574D02*
X844403Y-290408D01*
X843092Y-289824D01*
X841564Y-289533D01*
X840036Y-290116D01*
X838726Y-291282D01*
X837852Y-293032D01*
X837416Y-295366D01*
X837852Y-297699D01*
X838726Y-299449D01*
X840036Y-300616D01*
X841564Y-301199D01*
X843092Y-300907D01*
X844403Y-300033D01*
X845276Y-298866D01*
G01X854261Y-306449D02*
X855571Y-307032D01*
X857318Y-306449D01*
X858409Y-305283D01*
X859283Y-303824D01*
X860592Y-299158D01*
X863431Y-289533D01*
G01X856444D02*
X860592Y-299158D01*
G01X873071Y-293324D02*
X880058D01*
X879403Y-291282D01*
X878311Y-290116D01*
X876783Y-289533D01*
X875254Y-289824D01*
X873944Y-290699D01*
X873071Y-292741D01*
X872634Y-294491D01*
Y-296241D01*
X873071Y-297991D01*
X874163Y-299741D01*
X875473Y-300907D01*
X877001Y-301199D01*
X878529Y-300616D01*
X880058Y-298866D01*
G01X890789Y-301199D02*
Y-289533D01*
G01Y-291866D02*
X891881Y-290699D01*
X892973Y-289824D01*
X894501Y-289533D01*
X895592Y-289824D01*
X896903Y-290699D01*
G01X959846Y-328699D02*
X962902Y-346199D01*
X966396Y-328699D01*
X969889Y-346199D01*
X972946Y-328699D01*
G01X979529Y-346199D02*
Y-328699D01*
X984769D01*
X986516Y-329574D01*
X987826Y-331616D01*
X988263Y-333949D01*
X987826Y-336282D01*
X986734Y-338032D01*
X984769Y-338908D01*
X979529D01*
G01X996811Y-346199D02*
Y-328699D01*
G01X1005981D02*
Y-346199D01*
G01Y-337449D02*
X996811D01*
G01X1016058Y-340366D02*
X1021734D01*
G01X1031593Y-346199D02*
Y-328699D01*
G01X1039889D02*
X1031593Y-339491D01*
G01X1041199Y-346199D02*
X1035304Y-334533D01*
G01X1058263Y-346199D02*
X1049529D01*
Y-328699D01*
X1058263D01*
G01X1054769Y-337157D02*
X1049529D01*
G01X1066374Y-346199D02*
Y-328699D01*
X1076418Y-346199D01*
Y-328699D01*
G01X1083874Y-346199D02*
Y-328699D01*
X1093918Y-346199D01*
Y-328699D01*
G01X961593Y-301199D02*
Y-283699D01*
X965959D01*
X967706Y-284574D01*
X969016Y-285741D01*
X970108Y-287490D01*
X970981Y-289533D01*
X971199Y-292449D01*
X970981Y-295366D01*
X970108Y-297408D01*
X969016Y-299158D01*
X967706Y-300324D01*
X965959Y-301199D01*
X961593D01*
G01X980621Y-293324D02*
X987608D01*
X986953Y-291282D01*
X985861Y-290116D01*
X984333Y-289533D01*
X982804Y-289824D01*
X981494Y-290699D01*
X980621Y-292741D01*
X980184Y-294491D01*
Y-296241D01*
X980621Y-297991D01*
X981713Y-299741D01*
X983023Y-300907D01*
X984551Y-301199D01*
X986079Y-300616D01*
X987608Y-298866D01*
G01X998121Y-299158D02*
X999213Y-300324D01*
X1000741Y-301199D01*
X1002051D01*
X1003361Y-300616D01*
X1004234Y-299741D01*
X1004671Y-298575D01*
X1004453Y-296824D01*
X1003579Y-295949D01*
X999649Y-294199D01*
X998776Y-292157D01*
X999213Y-290699D01*
X1000086Y-289824D01*
X1001396Y-289533D01*
X1002706Y-289824D01*
X1004016Y-290699D01*
G01X1018896Y-289533D02*
Y-301199D01*
G01Y-284866D02*
X1018459Y-284574D01*
Y-283991D01*
X1018896Y-283699D01*
X1019333Y-283991D01*
Y-284574D01*
X1018896Y-284866D01*
G01X1033339Y-305574D02*
X1034868Y-306741D01*
X1036614Y-307032D01*
X1038142Y-306741D01*
X1039453Y-305283D01*
X1040326Y-303241D01*
Y-289533D01*
G01Y-291866D02*
X1039453Y-290699D01*
X1038142Y-289824D01*
X1036614Y-289533D01*
X1034868Y-290116D01*
X1033776Y-291282D01*
X1032902Y-293324D01*
X1032466Y-295366D01*
X1032684Y-297116D01*
X1033558Y-299158D01*
X1034868Y-300616D01*
X1036614Y-301199D01*
X1037924Y-300907D01*
X1039453Y-299741D01*
X1040326Y-298575D01*
G01X1050184Y-301199D02*
Y-289533D01*
G01Y-292449D02*
X1051058Y-290991D01*
X1052368Y-289824D01*
X1054114Y-289533D01*
X1055642Y-289824D01*
X1056953Y-290991D01*
X1057608Y-293032D01*
Y-301199D01*
G01X1068121Y-293324D02*
X1075108D01*
X1074453Y-291282D01*
X1073361Y-290116D01*
X1071833Y-289533D01*
X1070304Y-289824D01*
X1068994Y-290699D01*
X1068121Y-292741D01*
X1067684Y-294491D01*
Y-296241D01*
X1068121Y-297991D01*
X1069213Y-299741D01*
X1070523Y-300907D01*
X1072051Y-301199D01*
X1073579Y-300616D01*
X1075108Y-298866D01*
G01X1085839Y-301199D02*
Y-289533D01*
G01Y-291866D02*
X1086931Y-290699D01*
X1088023Y-289824D01*
X1089551Y-289533D01*
X1090642Y-289824D01*
X1091953Y-290699D01*
G01X1132596Y-346199D02*
Y-328699D01*
X1129976Y-332199D01*
G01Y-346199D02*
X1135216D01*
G01X1150096D02*
Y-328699D01*
X1147476Y-332199D01*
G01Y-346199D02*
X1152716D01*
G01X1163666Y-346782D02*
X1171526Y-328699D01*
G01X1185096Y-346199D02*
Y-328699D01*
X1182476Y-332199D01*
G01Y-346199D02*
X1187716D01*
G01X1198448Y-338908D02*
X1199976Y-336866D01*
X1201286Y-335699D01*
X1203033Y-335116D01*
X1204561Y-335699D01*
X1205653Y-336866D01*
X1206526Y-338616D01*
X1206744Y-340657D01*
X1206526Y-342408D01*
X1205653Y-344158D01*
X1204342Y-345616D01*
X1202814Y-346199D01*
X1201068Y-345616D01*
X1199539Y-343866D01*
X1198666Y-341241D01*
X1198448Y-338324D01*
X1198884Y-334533D01*
X1199539Y-332490D01*
X1200631Y-330449D01*
X1202159Y-328991D01*
X1203688Y-328699D01*
X1205216Y-329282D01*
X1206308Y-330741D01*
G01X1216166Y-346782D02*
X1224026Y-328699D01*
G01X1233448Y-331616D02*
X1234758Y-329866D01*
X1236286Y-328991D01*
X1238033Y-328699D01*
X1240216Y-329282D01*
X1241744Y-330741D01*
X1242181Y-332490D01*
X1241963Y-334241D01*
X1241089Y-335699D01*
X1236723Y-338616D01*
X1234758Y-340657D01*
X1233448Y-343575D01*
X1233011Y-346199D01*
X1242181D01*
G01X1255096Y-328699D02*
X1253349Y-329282D01*
X1252039Y-330741D01*
X1251166Y-332490D01*
X1250511Y-334824D01*
X1250293Y-337449D01*
X1250511Y-340074D01*
X1251166Y-342408D01*
X1252039Y-344158D01*
X1253349Y-345616D01*
X1255096Y-346199D01*
X1256842Y-345616D01*
X1258153Y-344158D01*
X1259026Y-342408D01*
X1259681Y-340074D01*
X1259899Y-337449D01*
X1259681Y-334824D01*
X1259026Y-332490D01*
X1258153Y-330741D01*
X1256842Y-329282D01*
X1255096Y-328699D01*
G01X1272596Y-346199D02*
Y-328699D01*
X1269976Y-332199D01*
G01Y-346199D02*
X1275216D01*
G01X1285948Y-338908D02*
X1287476Y-336866D01*
X1288786Y-335699D01*
X1290533Y-335116D01*
X1292061Y-335699D01*
X1293153Y-336866D01*
X1294026Y-338616D01*
X1294244Y-340657D01*
X1294026Y-342408D01*
X1293153Y-344158D01*
X1291842Y-345616D01*
X1290314Y-346199D01*
X1288568Y-345616D01*
X1287039Y-343866D01*
X1286166Y-341241D01*
X1285948Y-338324D01*
X1286384Y-334533D01*
X1287039Y-332490D01*
X1288131Y-330449D01*
X1289659Y-328991D01*
X1291188Y-328699D01*
X1292716Y-329282D01*
X1293808Y-330741D01*
G01X1180293Y-301199D02*
Y-283699D01*
X1184659D01*
X1186406Y-284574D01*
X1187716Y-285741D01*
X1188808Y-287490D01*
X1189681Y-289533D01*
X1189899Y-292449D01*
X1189681Y-295366D01*
X1188808Y-297408D01*
X1187716Y-299158D01*
X1186406Y-300324D01*
X1184659Y-301199D01*
X1180293D01*
G01X1206526D02*
Y-289533D01*
G01Y-291574D02*
X1205653Y-290408D01*
X1204342Y-289824D01*
X1202814Y-289533D01*
X1201286Y-290116D01*
X1199976Y-291282D01*
X1199102Y-293032D01*
X1198666Y-295366D01*
X1199102Y-297699D01*
X1199976Y-299449D01*
X1201286Y-300616D01*
X1202814Y-301199D01*
X1204342Y-300907D01*
X1205653Y-300033D01*
X1206526Y-298866D01*
G01X1220096Y-283699D02*
Y-301199D01*
G01X1217039Y-289533D02*
X1223153D01*
G01X1234321Y-293324D02*
X1241308D01*
X1240653Y-291282D01*
X1239561Y-290116D01*
X1238033Y-289533D01*
X1236504Y-289824D01*
X1235194Y-290699D01*
X1234321Y-292741D01*
X1233884Y-294491D01*
Y-296241D01*
X1234321Y-297991D01*
X1235413Y-299741D01*
X1236723Y-300907D01*
X1238251Y-301199D01*
X1239779Y-300616D01*
X1241308Y-298866D01*
M02*
